(lib_symbols
	(symbol "AP62301_TSOT_1" (in_bom yes) (on_board yes)
      (property "Reference" "U" (at 35.56 -2.54 0)
        (effects (font (size 1.27 1.27) (thickness 0.15)) (justify left bottom))
      )
      (property "Value" "AP62301_TSOT" (at 35.56 -7.62 0)
        (effects (font (size 1.27 1.27) (thickness 0.15)) (justify left bottom) hide)
      )
      (property "Footprint" "antmicro-footprints:TSOT23-6" (at 35.56 -10.16 0)
        (effects (font (size 1.27 1.27) (thickness 0.15)) (justify left bottom) hide)
      )
      (property "Datasheet" "https://www.diodes.com/assets/Datasheets/AP62300_AP62301_AP62300T.pdf" (at 35.56 -12.7 0)
        (effects (font (size 1.27 1.27) (thickness 0.15)) (justify left bottom) hide)
      )
      (property "MPN" "AP62301WU-7" (at 35.56 -5.08 0)
        (effects (font (size 1.27 1.27) (thickness 0.15)) (justify left bottom))
      )
      (property "Manufacturer" "Diodes Incorporated" (at 35.56 -15.24 0)
        (effects (font (size 1.27 1.27) (thickness 0.15)) (justify left bottom) hide)
      )
      (property "Author" "Antmicro" (at 35.56 -17.78 0)
        (effects (font (size 1.27 1.27) (thickness 0.15)) (justify left bottom) hide)
      )
      (property "License" "Apache-2.0" (at 35.56 -20.32 0)
        (effects (font (size 1.27 1.27) (thickness 0.15)) (justify left bottom) hide)
      )
      (property "ki_keywords" "SMT, PMIC, IC, VOLTAGE" (at 0 0 0)
        (effects (font (size 1.27 1.27)) hide)
      )
      (property "ki_description" "DC-DC Switching Synchronous Buck Regulator, Adjustable, 4.2V-18Vin, 0.8V-7V/3A out, TSOT-26-6" (at 0 0 0)
        (effects (font (size 1.27 1.27)) hide)
      )
      (symbol "AP62301_TSOT_1_1_1"
        (rectangle (start 2.54 2.54) (end 17.78 -12.7)
          (stroke (width 0.254) (type default))
          (fill (type background))
        )
        (pin power_in line (at 0 -10.16 0) (length 2.54)
          (name "GND" (effects (font (size 1.27 1.27))))
          (number "1" (effects (font (size 1.27 1.27))))
        )
        (pin power_out line (at 20.32 0 180) (length 2.54)
          (name "SW" (effects (font (size 1.27 1.27))))
          (number "2" (effects (font (size 1.27 1.27))))
        )
        (pin power_in line (at 0 0 0) (length 2.54)
          (name "VIN" (effects (font (size 1.27 1.27))))
          (number "3" (effects (font (size 1.27 1.27))))
        )
        (pin input line (at 20.32 -10.16 180) (length 2.54)
          (name "FB" (effects (font (size 1.27 1.27))))
          (number "4" (effects (font (size 1.27 1.27))))
        )
        (pin input line (at 0 -5.08 0) (length 2.54)
          (name "EN" (effects (font (size 1.27 1.27))))
          (number "5" (effects (font (size 1.27 1.27))))
        )
        (pin output line (at 20.32 -5.08 180) (length 2.54)
          (name "BST" (effects (font (size 1.27 1.27))))
          (number "6" (effects (font (size 1.27 1.27))))
        )
      )
    )
	(symbol "C_100n_0402_1" (pin_numbers hide) (pin_names hide) (in_bom yes) (on_board yes)
      (property "Reference" "C" (at 20.32 -5.08 0)
        (effects (font (size 1.27 1.27) (thickness 0.15)) (justify left bottom))
      )
      (property "Value" "C_100n_0402" (at 20.32 -10.16 0)
        (effects (font (size 1.27 1.27) (thickness 0.15)) (justify left bottom) hide)
      )
      (property "Footprint" "antmicro-footprints:C_0402_1005Metric" (at 20.32 -12.7 0)
        (effects (font (size 1.27 1.27) (thickness 0.15)) (justify left bottom) hide)
      )
      (property "Datasheet" "https://www.murata.com/products/productdetail?partno=GRM155R61H104KE14%23" (at 20.32 -15.24 0)
        (effects (font (size 1.27 1.27) (thickness 0.15)) (justify left bottom) hide)
      )
      (property "MPN" "GRM155R61H104KE14D" (at 20.32 -17.78 0)
        (effects (font (size 1.27 1.27) (thickness 0.15)) (justify left bottom) hide)
      )
      (property "Manufacturer" "Murata" (at 20.32 -20.32 0)
        (effects (font (size 1.27 1.27) (thickness 0.15)) (justify left bottom) hide)
      )
      (property "License" "Apache-2.0" (at 20.32 -22.86 0)
        (effects (font (size 1.27 1.27) (thickness 0.15)) (justify left bottom) hide)
      )
      (property "Author" "Antmicro" (at 20.32 -25.4 0)
        (effects (font (size 1.27 1.27) (thickness 0.15)) (justify left bottom) hide)
      )
      (property "Val" "100n" (at 20.32 -7.62 0)
        (effects (font (size 1.27 1.27) (thickness 0.15)) (justify left bottom))
      )
      (property "Voltage" "50V" (at 20.32 -27.94 0)
        (effects (font (size 1.27 1.27)) (justify left bottom) hide)
      )
      (property "Dielectric" "X5R" (at 20.32 -30.48 0)
        (effects (font (size 1.27 1.27)) (justify left bottom) hide)
      )
      (property "ki_keywords" "0402, SMT, CAPACITOR, PASSIVE, CERAMIC, MLCC" (at 0 0 0)
        (effects (font (size 1.27 1.27)) hide)
      )
      (property "ki_description" "SMD Multilayer Ceramic Capacitor, 0.1 µF, 50 V, 0402 [1005 Metric], ± 10%, X5R, GRM Series" (at 0 0 0)
        (effects (font (size 1.27 1.27)) hide)
      )
      (symbol "C_100n_0402_1_0_1"
        (polyline
          (pts
            (xy 2.032 -1.524)
            (xy 2.032 1.524)
          )
          (stroke (width 0.3048) (type default))
          (fill (type none))
        )
        (polyline
          (pts
            (xy 3.048 -1.524)
            (xy 3.048 1.524)
          )
          (stroke (width 0.3302) (type default))
          (fill (type none))
        )
      )
      (symbol "C_100n_0402_1_1_1"
        (pin passive line (at 0 0 0) (length 2.032)
          (name "~" (effects (font (size 1.27 1.27))))
          (number "1" (effects (font (size 1.27 1.27))))
        )
        (pin passive line (at 5.08 0 180) (length 2.032)
          (name "~" (effects (font (size 1.27 1.27))))
          (number "2" (effects (font (size 1.27 1.27))))
        )
      )
    )
	(symbol "C_100n_0402_10" (pin_numbers hide) (pin_names hide) (in_bom yes) (on_board yes)
      (property "Reference" "C" (at 20.32 -5.08 0)
        (effects (font (size 1.27 1.27) (thickness 0.15)) (justify left bottom))
      )
      (property "Value" "C_100n_0402" (at 20.32 -10.16 0)
        (effects (font (size 1.27 1.27) (thickness 0.15)) (justify left bottom) hide)
      )
      (property "Footprint" "antmicro-footprints:C_0402_1005Metric" (at 20.32 -12.7 0)
        (effects (font (size 1.27 1.27) (thickness 0.15)) (justify left bottom) hide)
      )
      (property "Datasheet" "https://www.murata.com/products/productdetail?partno=GRM155R61H104KE14%23" (at 20.32 -15.24 0)
        (effects (font (size 1.27 1.27) (thickness 0.15)) (justify left bottom) hide)
      )
      (property "MPN" "GRM155R61H104KE14D" (at 20.32 -17.78 0)
        (effects (font (size 1.27 1.27) (thickness 0.15)) (justify left bottom) hide)
      )
      (property "Manufacturer" "Murata" (at 20.32 -20.32 0)
        (effects (font (size 1.27 1.27) (thickness 0.15)) (justify left bottom) hide)
      )
      (property "License" "Apache-2.0" (at 20.32 -22.86 0)
        (effects (font (size 1.27 1.27) (thickness 0.15)) (justify left bottom) hide)
      )
      (property "Author" "Antmicro" (at 20.32 -25.4 0)
        (effects (font (size 1.27 1.27) (thickness 0.15)) (justify left bottom) hide)
      )
      (property "Val" "100n" (at 20.32 -7.62 0)
        (effects (font (size 1.27 1.27) (thickness 0.15)) (justify left bottom))
      )
      (property "Voltage" "50V" (at 20.32 -27.94 0)
        (effects (font (size 1.27 1.27)) (justify left bottom) hide)
      )
      (property "Dielectric" "X5R" (at 20.32 -30.48 0)
        (effects (font (size 1.27 1.27)) (justify left bottom) hide)
      )
      (property "ki_keywords" "0402, SMT, CAPACITOR, PASSIVE, CERAMIC, MLCC" (at 0 0 0)
        (effects (font (size 1.27 1.27)) hide)
      )
      (property "ki_description" "SMD Multilayer Ceramic Capacitor, 0.1 µF, 50 V, 0402 [1005 Metric], ± 10%, X5R, GRM Series" (at 0 0 0)
        (effects (font (size 1.27 1.27)) hide)
      )
      (symbol "C_100n_0402_10_0_1"
        (polyline
          (pts
            (xy 2.032 -1.524)
            (xy 2.032 1.524)
          )
          (stroke (width 0.3048) (type default))
          (fill (type none))
        )
        (polyline
          (pts
            (xy 3.048 -1.524)
            (xy 3.048 1.524)
          )
          (stroke (width 0.3302) (type default))
          (fill (type none))
        )
      )
      (symbol "C_100n_0402_10_1_1"
        (pin passive line (at 0 0 0) (length 2.032)
          (name "~" (effects (font (size 1.27 1.27))))
          (number "1" (effects (font (size 1.27 1.27))))
        )
        (pin passive line (at 5.08 0 180) (length 2.032)
          (name "~" (effects (font (size 1.27 1.27))))
          (number "2" (effects (font (size 1.27 1.27))))
        )
      )
    )
	(symbol "C_100n_0402_11" (pin_numbers hide) (pin_names hide) (in_bom yes) (on_board yes)
      (property "Reference" "C" (at 20.32 -5.08 0)
        (effects (font (size 1.27 1.27) (thickness 0.15)) (justify left bottom))
      )
      (property "Value" "C_100n_0402" (at 20.32 -10.16 0)
        (effects (font (size 1.27 1.27) (thickness 0.15)) (justify left bottom) hide)
      )
      (property "Footprint" "antmicro-footprints:C_0402_1005Metric" (at 20.32 -12.7 0)
        (effects (font (size 1.27 1.27) (thickness 0.15)) (justify left bottom) hide)
      )
      (property "Datasheet" "https://www.murata.com/products/productdetail?partno=GRM155R61H104KE14%23" (at 20.32 -15.24 0)
        (effects (font (size 1.27 1.27) (thickness 0.15)) (justify left bottom) hide)
      )
      (property "MPN" "GRM155R61H104KE14D" (at 20.32 -17.78 0)
        (effects (font (size 1.27 1.27) (thickness 0.15)) (justify left bottom) hide)
      )
      (property "Manufacturer" "Murata" (at 20.32 -20.32 0)
        (effects (font (size 1.27 1.27) (thickness 0.15)) (justify left bottom) hide)
      )
      (property "License" "Apache-2.0" (at 20.32 -22.86 0)
        (effects (font (size 1.27 1.27) (thickness 0.15)) (justify left bottom) hide)
      )
      (property "Author" "Antmicro" (at 20.32 -25.4 0)
        (effects (font (size 1.27 1.27) (thickness 0.15)) (justify left bottom) hide)
      )
      (property "Val" "100n" (at 20.32 -7.62 0)
        (effects (font (size 1.27 1.27) (thickness 0.15)) (justify left bottom))
      )
      (property "Voltage" "50V" (at 20.32 -27.94 0)
        (effects (font (size 1.27 1.27)) (justify left bottom) hide)
      )
      (property "Dielectric" "X5R" (at 20.32 -30.48 0)
        (effects (font (size 1.27 1.27)) (justify left bottom) hide)
      )
      (property "ki_keywords" "0402, SMT, CAPACITOR, PASSIVE, CERAMIC, MLCC" (at 0 0 0)
        (effects (font (size 1.27 1.27)) hide)
      )
      (property "ki_description" "SMD Multilayer Ceramic Capacitor, 0.1 µF, 50 V, 0402 [1005 Metric], ± 10%, X5R, GRM Series" (at 0 0 0)
        (effects (font (size 1.27 1.27)) hide)
      )
      (symbol "C_100n_0402_11_0_1"
        (polyline
          (pts
            (xy 2.032 -1.524)
            (xy 2.032 1.524)
          )
          (stroke (width 0.3048) (type default))
          (fill (type none))
        )
        (polyline
          (pts
            (xy 3.048 -1.524)
            (xy 3.048 1.524)
          )
          (stroke (width 0.3302) (type default))
          (fill (type none))
        )
      )
      (symbol "C_100n_0402_11_1_1"
        (pin passive line (at 0 0 0) (length 2.032)
          (name "~" (effects (font (size 1.27 1.27))))
          (number "1" (effects (font (size 1.27 1.27))))
        )
        (pin passive line (at 5.08 0 180) (length 2.032)
          (name "~" (effects (font (size 1.27 1.27))))
          (number "2" (effects (font (size 1.27 1.27))))
        )
      )
    )
	(symbol "C_100n_0402_12" (pin_numbers hide) (pin_names hide) (in_bom yes) (on_board yes)
      (property "Reference" "C" (at 20.32 -5.08 0)
        (effects (font (size 1.27 1.27) (thickness 0.15)) (justify left bottom))
      )
      (property "Value" "C_100n_0402" (at 20.32 -10.16 0)
        (effects (font (size 1.27 1.27) (thickness 0.15)) (justify left bottom) hide)
      )
      (property "Footprint" "antmicro-footprints:C_0402_1005Metric" (at 20.32 -12.7 0)
        (effects (font (size 1.27 1.27) (thickness 0.15)) (justify left bottom) hide)
      )
      (property "Datasheet" "https://www.murata.com/products/productdetail?partno=GRM155R61H104KE14%23" (at 20.32 -15.24 0)
        (effects (font (size 1.27 1.27) (thickness 0.15)) (justify left bottom) hide)
      )
      (property "MPN" "GRM155R61H104KE14D" (at 20.32 -17.78 0)
        (effects (font (size 1.27 1.27) (thickness 0.15)) (justify left bottom) hide)
      )
      (property "Manufacturer" "Murata" (at 20.32 -20.32 0)
        (effects (font (size 1.27 1.27) (thickness 0.15)) (justify left bottom) hide)
      )
      (property "License" "Apache-2.0" (at 20.32 -22.86 0)
        (effects (font (size 1.27 1.27) (thickness 0.15)) (justify left bottom) hide)
      )
      (property "Author" "Antmicro" (at 20.32 -25.4 0)
        (effects (font (size 1.27 1.27) (thickness 0.15)) (justify left bottom) hide)
      )
      (property "Val" "100n" (at 20.32 -7.62 0)
        (effects (font (size 1.27 1.27) (thickness 0.15)) (justify left bottom))
      )
      (property "Voltage" "50V" (at 20.32 -27.94 0)
        (effects (font (size 1.27 1.27)) (justify left bottom) hide)
      )
      (property "Dielectric" "X5R" (at 20.32 -30.48 0)
        (effects (font (size 1.27 1.27)) (justify left bottom) hide)
      )
      (property "ki_keywords" "0402, SMT, CAPACITOR, PASSIVE, CERAMIC, MLCC" (at 0 0 0)
        (effects (font (size 1.27 1.27)) hide)
      )
      (property "ki_description" "SMD Multilayer Ceramic Capacitor, 0.1 µF, 50 V, 0402 [1005 Metric], ± 10%, X5R, GRM Series" (at 0 0 0)
        (effects (font (size 1.27 1.27)) hide)
      )
      (symbol "C_100n_0402_12_0_1"
        (polyline
          (pts
            (xy 2.032 -1.524)
            (xy 2.032 1.524)
          )
          (stroke (width 0.3048) (type default))
          (fill (type none))
        )
        (polyline
          (pts
            (xy 3.048 -1.524)
            (xy 3.048 1.524)
          )
          (stroke (width 0.3302) (type default))
          (fill (type none))
        )
      )
      (symbol "C_100n_0402_12_1_1"
        (pin passive line (at 0 0 0) (length 2.032)
          (name "~" (effects (font (size 1.27 1.27))))
          (number "1" (effects (font (size 1.27 1.27))))
        )
        (pin passive line (at 5.08 0 180) (length 2.032)
          (name "~" (effects (font (size 1.27 1.27))))
          (number "2" (effects (font (size 1.27 1.27))))
        )
      )
    )
	(symbol "C_100n_0402_2" (pin_numbers hide) (pin_names hide) (in_bom yes) (on_board yes)
      (property "Reference" "C" (at 20.32 -5.08 0)
        (effects (font (size 1.27 1.27) (thickness 0.15)) (justify left bottom))
      )
      (property "Value" "C_100n_0402" (at 20.32 -10.16 0)
        (effects (font (size 1.27 1.27) (thickness 0.15)) (justify left bottom) hide)
      )
      (property "Footprint" "antmicro-footprints:C_0402_1005Metric" (at 20.32 -12.7 0)
        (effects (font (size 1.27 1.27) (thickness 0.15)) (justify left bottom) hide)
      )
      (property "Datasheet" "https://www.murata.com/products/productdetail?partno=GRM155R61H104KE14%23" (at 20.32 -15.24 0)
        (effects (font (size 1.27 1.27) (thickness 0.15)) (justify left bottom) hide)
      )
      (property "MPN" "GRM155R61H104KE14D" (at 20.32 -17.78 0)
        (effects (font (size 1.27 1.27) (thickness 0.15)) (justify left bottom) hide)
      )
      (property "Manufacturer" "Murata" (at 20.32 -20.32 0)
        (effects (font (size 1.27 1.27) (thickness 0.15)) (justify left bottom) hide)
      )
      (property "License" "Apache-2.0" (at 20.32 -22.86 0)
        (effects (font (size 1.27 1.27) (thickness 0.15)) (justify left bottom) hide)
      )
      (property "Author" "Antmicro" (at 20.32 -25.4 0)
        (effects (font (size 1.27 1.27) (thickness 0.15)) (justify left bottom) hide)
      )
      (property "Val" "100n" (at 20.32 -7.62 0)
        (effects (font (size 1.27 1.27) (thickness 0.15)) (justify left bottom))
      )
      (property "Voltage" "50V" (at 20.32 -27.94 0)
        (effects (font (size 1.27 1.27)) (justify left bottom) hide)
      )
      (property "Dielectric" "X5R" (at 20.32 -30.48 0)
        (effects (font (size 1.27 1.27)) (justify left bottom) hide)
      )
      (property "ki_keywords" "0402, SMT, CAPACITOR, PASSIVE, CERAMIC, MLCC" (at 0 0 0)
        (effects (font (size 1.27 1.27)) hide)
      )
      (property "ki_description" "SMD Multilayer Ceramic Capacitor, 0.1 µF, 50 V, 0402 [1005 Metric], ± 10%, X5R, GRM Series" (at 0 0 0)
        (effects (font (size 1.27 1.27)) hide)
      )
      (symbol "C_100n_0402_2_0_1"
        (polyline
          (pts
            (xy 2.032 -1.524)
            (xy 2.032 1.524)
          )
          (stroke (width 0.3048) (type default))
          (fill (type none))
        )
        (polyline
          (pts
            (xy 3.048 -1.524)
            (xy 3.048 1.524)
          )
          (stroke (width 0.3302) (type default))
          (fill (type none))
        )
      )
      (symbol "C_100n_0402_2_1_1"
        (pin passive line (at 0 0 0) (length 2.032)
          (name "~" (effects (font (size 1.27 1.27))))
          (number "1" (effects (font (size 1.27 1.27))))
        )
        (pin passive line (at 5.08 0 180) (length 2.032)
          (name "~" (effects (font (size 1.27 1.27))))
          (number "2" (effects (font (size 1.27 1.27))))
        )
      )
    )
	(symbol "C_100n_0402_3" (pin_numbers hide) (pin_names hide) (in_bom yes) (on_board yes)
      (property "Reference" "C" (at 20.32 -5.08 0)
        (effects (font (size 1.27 1.27) (thickness 0.15)) (justify left bottom))
      )
      (property "Value" "C_100n_0402" (at 20.32 -10.16 0)
        (effects (font (size 1.27 1.27) (thickness 0.15)) (justify left bottom) hide)
      )
      (property "Footprint" "antmicro-footprints:C_0402_1005Metric" (at 20.32 -12.7 0)
        (effects (font (size 1.27 1.27) (thickness 0.15)) (justify left bottom) hide)
      )
      (property "Datasheet" "https://www.murata.com/products/productdetail?partno=GRM155R61H104KE14%23" (at 20.32 -15.24 0)
        (effects (font (size 1.27 1.27) (thickness 0.15)) (justify left bottom) hide)
      )
      (property "MPN" "GRM155R61H104KE14D" (at 20.32 -17.78 0)
        (effects (font (size 1.27 1.27) (thickness 0.15)) (justify left bottom) hide)
      )
      (property "Manufacturer" "Murata" (at 20.32 -20.32 0)
        (effects (font (size 1.27 1.27) (thickness 0.15)) (justify left bottom) hide)
      )
      (property "License" "Apache-2.0" (at 20.32 -22.86 0)
        (effects (font (size 1.27 1.27) (thickness 0.15)) (justify left bottom) hide)
      )
      (property "Author" "Antmicro" (at 20.32 -25.4 0)
        (effects (font (size 1.27 1.27) (thickness 0.15)) (justify left bottom) hide)
      )
      (property "Val" "100n" (at 20.32 -7.62 0)
        (effects (font (size 1.27 1.27) (thickness 0.15)) (justify left bottom))
      )
      (property "Voltage" "50V" (at 20.32 -27.94 0)
        (effects (font (size 1.27 1.27)) (justify left bottom) hide)
      )
      (property "Dielectric" "X5R" (at 20.32 -30.48 0)
        (effects (font (size 1.27 1.27)) (justify left bottom) hide)
      )
      (property "ki_keywords" "0402, SMT, CAPACITOR, PASSIVE, CERAMIC, MLCC" (at 0 0 0)
        (effects (font (size 1.27 1.27)) hide)
      )
      (property "ki_description" "SMD Multilayer Ceramic Capacitor, 0.1 µF, 50 V, 0402 [1005 Metric], ± 10%, X5R, GRM Series" (at 0 0 0)
        (effects (font (size 1.27 1.27)) hide)
      )
      (symbol "C_100n_0402_3_0_1"
        (polyline
          (pts
            (xy 2.032 -1.524)
            (xy 2.032 1.524)
          )
          (stroke (width 0.3048) (type default))
          (fill (type none))
        )
        (polyline
          (pts
            (xy 3.048 -1.524)
            (xy 3.048 1.524)
          )
          (stroke (width 0.3302) (type default))
          (fill (type none))
        )
      )
      (symbol "C_100n_0402_3_1_1"
        (pin passive line (at 0 0 0) (length 2.032)
          (name "~" (effects (font (size 1.27 1.27))))
          (number "1" (effects (font (size 1.27 1.27))))
        )
        (pin passive line (at 5.08 0 180) (length 2.032)
          (name "~" (effects (font (size 1.27 1.27))))
          (number "2" (effects (font (size 1.27 1.27))))
        )
      )
    )
	(symbol "C_100n_0402_4" (pin_numbers hide) (pin_names hide) (in_bom yes) (on_board yes)
      (property "Reference" "C" (at 20.32 -5.08 0)
        (effects (font (size 1.27 1.27) (thickness 0.15)) (justify left bottom))
      )
      (property "Value" "C_100n_0402" (at 20.32 -10.16 0)
        (effects (font (size 1.27 1.27) (thickness 0.15)) (justify left bottom) hide)
      )
      (property "Footprint" "antmicro-footprints:C_0402_1005Metric" (at 20.32 -12.7 0)
        (effects (font (size 1.27 1.27) (thickness 0.15)) (justify left bottom) hide)
      )
      (property "Datasheet" "https://www.murata.com/products/productdetail?partno=GRM155R61H104KE14%23" (at 20.32 -15.24 0)
        (effects (font (size 1.27 1.27) (thickness 0.15)) (justify left bottom) hide)
      )
      (property "MPN" "GRM155R61H104KE14D" (at 20.32 -17.78 0)
        (effects (font (size 1.27 1.27) (thickness 0.15)) (justify left bottom) hide)
      )
      (property "Manufacturer" "Murata" (at 20.32 -20.32 0)
        (effects (font (size 1.27 1.27) (thickness 0.15)) (justify left bottom) hide)
      )
      (property "License" "Apache-2.0" (at 20.32 -22.86 0)
        (effects (font (size 1.27 1.27) (thickness 0.15)) (justify left bottom) hide)
      )
      (property "Author" "Antmicro" (at 20.32 -25.4 0)
        (effects (font (size 1.27 1.27) (thickness 0.15)) (justify left bottom) hide)
      )
      (property "Val" "100n" (at 20.32 -7.62 0)
        (effects (font (size 1.27 1.27) (thickness 0.15)) (justify left bottom))
      )
      (property "Voltage" "50V" (at 20.32 -27.94 0)
        (effects (font (size 1.27 1.27)) (justify left bottom) hide)
      )
      (property "Dielectric" "X5R" (at 20.32 -30.48 0)
        (effects (font (size 1.27 1.27)) (justify left bottom) hide)
      )
      (property "ki_keywords" "0402, SMT, CAPACITOR, PASSIVE, CERAMIC, MLCC" (at 0 0 0)
        (effects (font (size 1.27 1.27)) hide)
      )
      (property "ki_description" "SMD Multilayer Ceramic Capacitor, 0.1 µF, 50 V, 0402 [1005 Metric], ± 10%, X5R, GRM Series" (at 0 0 0)
        (effects (font (size 1.27 1.27)) hide)
      )
      (symbol "C_100n_0402_4_0_1"
        (polyline
          (pts
            (xy 2.032 -1.524)
            (xy 2.032 1.524)
          )
          (stroke (width 0.3048) (type default))
          (fill (type none))
        )
        (polyline
          (pts
            (xy 3.048 -1.524)
            (xy 3.048 1.524)
          )
          (stroke (width 0.3302) (type default))
          (fill (type none))
        )
      )
      (symbol "C_100n_0402_4_1_1"
        (pin passive line (at 0 0 0) (length 2.032)
          (name "~" (effects (font (size 1.27 1.27))))
          (number "1" (effects (font (size 1.27 1.27))))
        )
        (pin passive line (at 5.08 0 180) (length 2.032)
          (name "~" (effects (font (size 1.27 1.27))))
          (number "2" (effects (font (size 1.27 1.27))))
        )
      )
    )
	(symbol "C_100n_0402_5" (pin_numbers hide) (pin_names hide) (in_bom yes) (on_board yes)
      (property "Reference" "C" (at 20.32 -5.08 0)
        (effects (font (size 1.27 1.27) (thickness 0.15)) (justify left bottom))
      )
      (property "Value" "C_100n_0402" (at 20.32 -10.16 0)
        (effects (font (size 1.27 1.27) (thickness 0.15)) (justify left bottom) hide)
      )
      (property "Footprint" "antmicro-footprints:C_0402_1005Metric" (at 20.32 -12.7 0)
        (effects (font (size 1.27 1.27) (thickness 0.15)) (justify left bottom) hide)
      )
      (property "Datasheet" "https://www.murata.com/products/productdetail?partno=GRM155R61H104KE14%23" (at 20.32 -15.24 0)
        (effects (font (size 1.27 1.27) (thickness 0.15)) (justify left bottom) hide)
      )
      (property "MPN" "GRM155R61H104KE14D" (at 20.32 -17.78 0)
        (effects (font (size 1.27 1.27) (thickness 0.15)) (justify left bottom) hide)
      )
      (property "Manufacturer" "Murata" (at 20.32 -20.32 0)
        (effects (font (size 1.27 1.27) (thickness 0.15)) (justify left bottom) hide)
      )
      (property "License" "Apache-2.0" (at 20.32 -22.86 0)
        (effects (font (size 1.27 1.27) (thickness 0.15)) (justify left bottom) hide)
      )
      (property "Author" "Antmicro" (at 20.32 -25.4 0)
        (effects (font (size 1.27 1.27) (thickness 0.15)) (justify left bottom) hide)
      )
      (property "Val" "100n" (at 20.32 -7.62 0)
        (effects (font (size 1.27 1.27) (thickness 0.15)) (justify left bottom))
      )
      (property "Voltage" "50V" (at 20.32 -27.94 0)
        (effects (font (size 1.27 1.27)) (justify left bottom) hide)
      )
      (property "Dielectric" "X5R" (at 20.32 -30.48 0)
        (effects (font (size 1.27 1.27)) (justify left bottom) hide)
      )
      (property "ki_keywords" "0402, SMT, CAPACITOR, PASSIVE, CERAMIC, MLCC" (at 0 0 0)
        (effects (font (size 1.27 1.27)) hide)
      )
      (property "ki_description" "SMD Multilayer Ceramic Capacitor, 0.1 µF, 50 V, 0402 [1005 Metric], ± 10%, X5R, GRM Series" (at 0 0 0)
        (effects (font (size 1.27 1.27)) hide)
      )
      (symbol "C_100n_0402_5_0_1"
        (polyline
          (pts
            (xy 2.032 -1.524)
            (xy 2.032 1.524)
          )
          (stroke (width 0.3048) (type default))
          (fill (type none))
        )
        (polyline
          (pts
            (xy 3.048 -1.524)
            (xy 3.048 1.524)
          )
          (stroke (width 0.3302) (type default))
          (fill (type none))
        )
      )
      (symbol "C_100n_0402_5_1_1"
        (pin passive line (at 0 0 0) (length 2.032)
          (name "~" (effects (font (size 1.27 1.27))))
          (number "1" (effects (font (size 1.27 1.27))))
        )
        (pin passive line (at 5.08 0 180) (length 2.032)
          (name "~" (effects (font (size 1.27 1.27))))
          (number "2" (effects (font (size 1.27 1.27))))
        )
      )
    )
	(symbol "C_100n_0402_6" (pin_numbers hide) (pin_names hide) (in_bom yes) (on_board yes)
      (property "Reference" "C" (at 20.32 -5.08 0)
        (effects (font (size 1.27 1.27) (thickness 0.15)) (justify left bottom))
      )
      (property "Value" "C_100n_0402" (at 20.32 -10.16 0)
        (effects (font (size 1.27 1.27) (thickness 0.15)) (justify left bottom) hide)
      )
      (property "Footprint" "antmicro-footprints:C_0402_1005Metric" (at 20.32 -12.7 0)
        (effects (font (size 1.27 1.27) (thickness 0.15)) (justify left bottom) hide)
      )
      (property "Datasheet" "https://www.murata.com/products/productdetail?partno=GRM155R61H104KE14%23" (at 20.32 -15.24 0)
        (effects (font (size 1.27 1.27) (thickness 0.15)) (justify left bottom) hide)
      )
      (property "MPN" "GRM155R61H104KE14D" (at 20.32 -17.78 0)
        (effects (font (size 1.27 1.27) (thickness 0.15)) (justify left bottom) hide)
      )
      (property "Manufacturer" "Murata" (at 20.32 -20.32 0)
        (effects (font (size 1.27 1.27) (thickness 0.15)) (justify left bottom) hide)
      )
      (property "License" "Apache-2.0" (at 20.32 -22.86 0)
        (effects (font (size 1.27 1.27) (thickness 0.15)) (justify left bottom) hide)
      )
      (property "Author" "Antmicro" (at 20.32 -25.4 0)
        (effects (font (size 1.27 1.27) (thickness 0.15)) (justify left bottom) hide)
      )
      (property "Val" "100n" (at 20.32 -7.62 0)
        (effects (font (size 1.27 1.27) (thickness 0.15)) (justify left bottom))
      )
      (property "Voltage" "50V" (at 20.32 -27.94 0)
        (effects (font (size 1.27 1.27)) (justify left bottom) hide)
      )
      (property "Dielectric" "X5R" (at 20.32 -30.48 0)
        (effects (font (size 1.27 1.27)) (justify left bottom) hide)
      )
      (property "ki_keywords" "0402, SMT, CAPACITOR, PASSIVE, CERAMIC, MLCC" (at 0 0 0)
        (effects (font (size 1.27 1.27)) hide)
      )
      (property "ki_description" "SMD Multilayer Ceramic Capacitor, 0.1 µF, 50 V, 0402 [1005 Metric], ± 10%, X5R, GRM Series" (at 0 0 0)
        (effects (font (size 1.27 1.27)) hide)
      )
      (symbol "C_100n_0402_6_0_1"
        (polyline
          (pts
            (xy 2.032 -1.524)
            (xy 2.032 1.524)
          )
          (stroke (width 0.3048) (type default))
          (fill (type none))
        )
        (polyline
          (pts
            (xy 3.048 -1.524)
            (xy 3.048 1.524)
          )
          (stroke (width 0.3302) (type default))
          (fill (type none))
        )
      )
      (symbol "C_100n_0402_6_1_1"
        (pin passive line (at 0 0 0) (length 2.032)
          (name "~" (effects (font (size 1.27 1.27))))
          (number "1" (effects (font (size 1.27 1.27))))
        )
        (pin passive line (at 5.08 0 180) (length 2.032)
          (name "~" (effects (font (size 1.27 1.27))))
          (number "2" (effects (font (size 1.27 1.27))))
        )
      )
    )
	(symbol "C_100n_0402_7" (pin_numbers hide) (pin_names hide) (in_bom yes) (on_board yes)
      (property "Reference" "C" (at 20.32 -5.08 0)
        (effects (font (size 1.27 1.27) (thickness 0.15)) (justify left bottom))
      )
      (property "Value" "C_100n_0402" (at 20.32 -10.16 0)
        (effects (font (size 1.27 1.27) (thickness 0.15)) (justify left bottom) hide)
      )
      (property "Footprint" "antmicro-footprints:C_0402_1005Metric" (at 20.32 -12.7 0)
        (effects (font (size 1.27 1.27) (thickness 0.15)) (justify left bottom) hide)
      )
      (property "Datasheet" "https://www.murata.com/products/productdetail?partno=GRM155R61H104KE14%23" (at 20.32 -15.24 0)
        (effects (font (size 1.27 1.27) (thickness 0.15)) (justify left bottom) hide)
      )
      (property "MPN" "GRM155R61H104KE14D" (at 20.32 -17.78 0)
        (effects (font (size 1.27 1.27) (thickness 0.15)) (justify left bottom) hide)
      )
      (property "Manufacturer" "Murata" (at 20.32 -20.32 0)
        (effects (font (size 1.27 1.27) (thickness 0.15)) (justify left bottom) hide)
      )
      (property "License" "Apache-2.0" (at 20.32 -22.86 0)
        (effects (font (size 1.27 1.27) (thickness 0.15)) (justify left bottom) hide)
      )
      (property "Author" "Antmicro" (at 20.32 -25.4 0)
        (effects (font (size 1.27 1.27) (thickness 0.15)) (justify left bottom) hide)
      )
      (property "Val" "100n" (at 20.32 -7.62 0)
        (effects (font (size 1.27 1.27) (thickness 0.15)) (justify left bottom))
      )
      (property "Voltage" "50V" (at 20.32 -27.94 0)
        (effects (font (size 1.27 1.27)) (justify left bottom) hide)
      )
      (property "Dielectric" "X5R" (at 20.32 -30.48 0)
        (effects (font (size 1.27 1.27)) (justify left bottom) hide)
      )
      (property "ki_keywords" "0402, SMT, CAPACITOR, PASSIVE, CERAMIC, MLCC" (at 0 0 0)
        (effects (font (size 1.27 1.27)) hide)
      )
      (property "ki_description" "SMD Multilayer Ceramic Capacitor, 0.1 µF, 50 V, 0402 [1005 Metric], ± 10%, X5R, GRM Series" (at 0 0 0)
        (effects (font (size 1.27 1.27)) hide)
      )
      (symbol "C_100n_0402_7_0_1"
        (polyline
          (pts
            (xy 2.032 -1.524)
            (xy 2.032 1.524)
          )
          (stroke (width 0.3048) (type default))
          (fill (type none))
        )
        (polyline
          (pts
            (xy 3.048 -1.524)
            (xy 3.048 1.524)
          )
          (stroke (width 0.3302) (type default))
          (fill (type none))
        )
      )
      (symbol "C_100n_0402_7_1_1"
        (pin passive line (at 0 0 0) (length 2.032)
          (name "~" (effects (font (size 1.27 1.27))))
          (number "1" (effects (font (size 1.27 1.27))))
        )
        (pin passive line (at 5.08 0 180) (length 2.032)
          (name "~" (effects (font (size 1.27 1.27))))
          (number "2" (effects (font (size 1.27 1.27))))
        )
      )
    )
	(symbol "C_100n_0402_8" (pin_numbers hide) (pin_names hide) (in_bom yes) (on_board yes)
      (property "Reference" "C" (at 20.32 -5.08 0)
        (effects (font (size 1.27 1.27) (thickness 0.15)) (justify left bottom))
      )
      (property "Value" "C_100n_0402" (at 20.32 -10.16 0)
        (effects (font (size 1.27 1.27) (thickness 0.15)) (justify left bottom) hide)
      )
      (property "Footprint" "antmicro-footprints:C_0402_1005Metric" (at 20.32 -12.7 0)
        (effects (font (size 1.27 1.27) (thickness 0.15)) (justify left bottom) hide)
      )
      (property "Datasheet" "https://www.murata.com/products/productdetail?partno=GRM155R61H104KE14%23" (at 20.32 -15.24 0)
        (effects (font (size 1.27 1.27) (thickness 0.15)) (justify left bottom) hide)
      )
      (property "MPN" "GRM155R61H104KE14D" (at 20.32 -17.78 0)
        (effects (font (size 1.27 1.27) (thickness 0.15)) (justify left bottom) hide)
      )
      (property "Manufacturer" "Murata" (at 20.32 -20.32 0)
        (effects (font (size 1.27 1.27) (thickness 0.15)) (justify left bottom) hide)
      )
      (property "License" "Apache-2.0" (at 20.32 -22.86 0)
        (effects (font (size 1.27 1.27) (thickness 0.15)) (justify left bottom) hide)
      )
      (property "Author" "Antmicro" (at 20.32 -25.4 0)
        (effects (font (size 1.27 1.27) (thickness 0.15)) (justify left bottom) hide)
      )
      (property "Val" "100n" (at 20.32 -7.62 0)
        (effects (font (size 1.27 1.27) (thickness 0.15)) (justify left bottom))
      )
      (property "Voltage" "50V" (at 20.32 -27.94 0)
        (effects (font (size 1.27 1.27)) (justify left bottom) hide)
      )
      (property "Dielectric" "X5R" (at 20.32 -30.48 0)
        (effects (font (size 1.27 1.27)) (justify left bottom) hide)
      )
      (property "ki_keywords" "0402, SMT, CAPACITOR, PASSIVE, CERAMIC, MLCC" (at 0 0 0)
        (effects (font (size 1.27 1.27)) hide)
      )
      (property "ki_description" "SMD Multilayer Ceramic Capacitor, 0.1 µF, 50 V, 0402 [1005 Metric], ± 10%, X5R, GRM Series" (at 0 0 0)
        (effects (font (size 1.27 1.27)) hide)
      )
      (symbol "C_100n_0402_8_0_1"
        (polyline
          (pts
            (xy 2.032 -1.524)
            (xy 2.032 1.524)
          )
          (stroke (width 0.3048) (type default))
          (fill (type none))
        )
        (polyline
          (pts
            (xy 3.048 -1.524)
            (xy 3.048 1.524)
          )
          (stroke (width 0.3302) (type default))
          (fill (type none))
        )
      )
      (symbol "C_100n_0402_8_1_1"
        (pin passive line (at 0 0 0) (length 2.032)
          (name "~" (effects (font (size 1.27 1.27))))
          (number "1" (effects (font (size 1.27 1.27))))
        )
        (pin passive line (at 5.08 0 180) (length 2.032)
          (name "~" (effects (font (size 1.27 1.27))))
          (number "2" (effects (font (size 1.27 1.27))))
        )
      )
    )
	(symbol "C_100n_0402_9" (pin_numbers hide) (pin_names hide) (in_bom yes) (on_board yes)
      (property "Reference" "C" (at 20.32 -5.08 0)
        (effects (font (size 1.27 1.27) (thickness 0.15)) (justify left bottom))
      )
      (property "Value" "C_100n_0402" (at 20.32 -10.16 0)
        (effects (font (size 1.27 1.27) (thickness 0.15)) (justify left bottom) hide)
      )
      (property "Footprint" "antmicro-footprints:C_0402_1005Metric" (at 20.32 -12.7 0)
        (effects (font (size 1.27 1.27) (thickness 0.15)) (justify left bottom) hide)
      )
      (property "Datasheet" "https://www.murata.com/products/productdetail?partno=GRM155R61H104KE14%23" (at 20.32 -15.24 0)
        (effects (font (size 1.27 1.27) (thickness 0.15)) (justify left bottom) hide)
      )
      (property "MPN" "GRM155R61H104KE14D" (at 20.32 -17.78 0)
        (effects (font (size 1.27 1.27) (thickness 0.15)) (justify left bottom) hide)
      )
      (property "Manufacturer" "Murata" (at 20.32 -20.32 0)
        (effects (font (size 1.27 1.27) (thickness 0.15)) (justify left bottom) hide)
      )
      (property "License" "Apache-2.0" (at 20.32 -22.86 0)
        (effects (font (size 1.27 1.27) (thickness 0.15)) (justify left bottom) hide)
      )
      (property "Author" "Antmicro" (at 20.32 -25.4 0)
        (effects (font (size 1.27 1.27) (thickness 0.15)) (justify left bottom) hide)
      )
      (property "Val" "100n" (at 20.32 -7.62 0)
        (effects (font (size 1.27 1.27) (thickness 0.15)) (justify left bottom))
      )
      (property "Voltage" "50V" (at 20.32 -27.94 0)
        (effects (font (size 1.27 1.27)) (justify left bottom) hide)
      )
      (property "Dielectric" "X5R" (at 20.32 -30.48 0)
        (effects (font (size 1.27 1.27)) (justify left bottom) hide)
      )
      (property "ki_keywords" "0402, SMT, CAPACITOR, PASSIVE, CERAMIC, MLCC" (at 0 0 0)
        (effects (font (size 1.27 1.27)) hide)
      )
      (property "ki_description" "SMD Multilayer Ceramic Capacitor, 0.1 µF, 50 V, 0402 [1005 Metric], ± 10%, X5R, GRM Series" (at 0 0 0)
        (effects (font (size 1.27 1.27)) hide)
      )
      (symbol "C_100n_0402_9_0_1"
        (polyline
          (pts
            (xy 2.032 -1.524)
            (xy 2.032 1.524)
          )
          (stroke (width 0.3048) (type default))
          (fill (type none))
        )
        (polyline
          (pts
            (xy 3.048 -1.524)
            (xy 3.048 1.524)
          )
          (stroke (width 0.3302) (type default))
          (fill (type none))
        )
      )
      (symbol "C_100n_0402_9_1_1"
        (pin passive line (at 0 0 0) (length 2.032)
          (name "~" (effects (font (size 1.27 1.27))))
          (number "1" (effects (font (size 1.27 1.27))))
        )
        (pin passive line (at 5.08 0 180) (length 2.032)
          (name "~" (effects (font (size 1.27 1.27))))
          (number "2" (effects (font (size 1.27 1.27))))
        )
      )
    )
	(symbol "C_10u_25V_0603_1" (pin_numbers hide) (pin_names hide) (in_bom yes) (on_board yes)
      (property "Reference" "C" (at 20.32 -5.08 0)
        (effects (font (size 1.27 1.27) (thickness 0.15)) (justify left bottom))
      )
      (property "Value" "C_10u_25V_0603" (at 20.32 -10.16 0)
        (effects (font (size 1.27 1.27) (thickness 0.15)) (justify left bottom) hide)
      )
      (property "Footprint" "antmicro-footprints:C_0603_1608Metric" (at 20.32 -12.7 0)
        (effects (font (size 1.27 1.27) (thickness 0.15)) (justify left bottom) hide)
      )
      (property "Datasheet" "https://product.tdk.com/en/search/capacitor/ceramic/mlcc/info?part_no=C1608X5R1E106M080AC" (at 20.32 -15.24 0)
        (effects (font (size 1.27 1.27) (thickness 0.15)) (justify left bottom) hide)
      )
      (property "MPN" "C1608X5R1E106M080AC" (at 20.32 -17.78 0)
        (effects (font (size 1.27 1.27) (thickness 0.15)) (justify left bottom) hide)
      )
      (property "Manufacturer" "TDK" (at 20.32 -20.32 0)
        (effects (font (size 1.27 1.27) (thickness 0.15)) (justify left bottom) hide)
      )
      (property "License" "Apache-2.0" (at 20.32 -22.86 0)
        (effects (font (size 1.27 1.27) (thickness 0.15)) (justify left bottom) hide)
      )
      (property "Author" "Antmicro" (at 20.32 -25.4 0)
        (effects (font (size 1.27 1.27) (thickness 0.15)) (justify left bottom) hide)
      )
      (property "Val" "10u" (at 20.32 -7.62 0)
        (effects (font (size 1.27 1.27) (thickness 0.15)) (justify left bottom))
      )
      (property "Voltage" "25V" (at 20.32 -27.94 0)
        (effects (font (size 1.27 1.27)) (justify left bottom) hide)
      )
      (property "Dielectric" "" (at 20.32 -30.48 0)
        (effects (font (size 1.27 1.27)) (justify left bottom) hide)
      )
      (property "ki_keywords" "0603, SMT, CAPACITOR, PASSIVE, CERAMIC, MLCC" (at 0 0 0)
        (effects (font (size 1.27 1.27)) hide)
      )
      (property "ki_description" "SMD Multilayer Ceramic Capacitor, 10 µF, 25 V, 0603 [1608 Metric], ± 20%, X5R, C" (at 0 0 0)
        (effects (font (size 1.27 1.27)) hide)
      )
      (symbol "C_10u_25V_0603_1_0_1"
        (polyline
          (pts
            (xy 2.032 -1.524)
            (xy 2.032 1.524)
          )
          (stroke (width 0.3048) (type default))
          (fill (type none))
        )
        (polyline
          (pts
            (xy 3.048 -1.524)
            (xy 3.048 1.524)
          )
          (stroke (width 0.3302) (type default))
          (fill (type none))
        )
      )
      (symbol "C_10u_25V_0603_1_1_1"
        (pin passive line (at 0 0 0) (length 2.032)
          (name "~" (effects (font (size 1.27 1.27))))
          (number "1" (effects (font (size 1.27 1.27))))
        )
        (pin passive line (at 5.08 0 180) (length 2.032)
          (name "~" (effects (font (size 1.27 1.27))))
          (number "2" (effects (font (size 1.27 1.27))))
        )
      )
    )
	(symbol "C_18p_0402_1" (pin_numbers hide) (pin_names hide) (in_bom yes) (on_board yes)
      (property "Reference" "C" (at 20.32 -5.08 0)
        (effects (font (size 1.27 1.27) (thickness 0.15)) (justify left bottom))
      )
      (property "Value" "C_18p_0402" (at 20.32 -10.16 0)
        (effects (font (size 1.27 1.27) (thickness 0.15)) (justify left bottom) hide)
      )
      (property "Footprint" "antmicro-footprints:C_0402_1005Metric" (at 20.32 -12.7 0)
        (effects (font (size 1.27 1.27) (thickness 0.15)) (justify left bottom) hide)
      )
      (property "Datasheet" "https://product.samsungsem.com/mlcc/CL05C180JB51PN.do" (at 20.32 -15.24 0)
        (effects (font (size 1.27 1.27) (thickness 0.15)) (justify left bottom) hide)
      )
      (property "MPN" "CL05C180JB51PNC" (at 20.32 -17.78 0)
        (effects (font (size 1.27 1.27) (thickness 0.15)) (justify left bottom) hide)
      )
      (property "Manufacturer" "Samsung Electro-Mechanics" (at 20.32 -20.32 0)
        (effects (font (size 1.27 1.27) (thickness 0.15)) (justify left bottom) hide)
      )
      (property "License" "Apache-2.0" (at 20.32 -22.86 0)
        (effects (font (size 1.27 1.27) (thickness 0.15)) (justify left bottom) hide)
      )
      (property "Author" "Antmicro" (at 20.32 -25.4 0)
        (effects (font (size 1.27 1.27) (thickness 0.15)) (justify left bottom) hide)
      )
      (property "Val" "18p" (at 20.32 -7.62 0)
        (effects (font (size 1.27 1.27) (thickness 0.15)) (justify left bottom))
      )
      (property "Voltage" "" (at 20.32 -27.94 0)
        (effects (font (size 1.27 1.27)) (justify left bottom) hide)
      )
      (property "Dielectric" "" (at 20.32 -30.48 0)
        (effects (font (size 1.27 1.27)) (justify left bottom) hide)
      )
      (property "ki_keywords" "0402, SMT, CAPACITOR, PASSIVE" (at 0 0 0)
        (effects (font (size 1.27 1.27)) hide)
      )
      (property "ki_description" "SMD Multilayer Ceramic Capacitor, 18 pF, 50 V, 0402 [1005 Metric], ± 5%, C0G / NP0, MC" (at 0 0 0)
        (effects (font (size 1.27 1.27)) hide)
      )
      (symbol "C_18p_0402_1_0_1"
        (polyline
          (pts
            (xy 2.032 -1.524)
            (xy 2.032 1.524)
          )
          (stroke (width 0.3048) (type default))
          (fill (type none))
        )
        (polyline
          (pts
            (xy 3.048 -1.524)
            (xy 3.048 1.524)
          )
          (stroke (width 0.3302) (type default))
          (fill (type none))
        )
      )
      (symbol "C_18p_0402_1_1_1"
        (pin passive line (at 0 0 0) (length 2.032)
          (name "~" (effects (font (size 1.27 1.27))))
          (number "1" (effects (font (size 1.27 1.27))))
        )
        (pin passive line (at 5.08 0 180) (length 2.032)
          (name "~" (effects (font (size 1.27 1.27))))
          (number "2" (effects (font (size 1.27 1.27))))
        )
      )
    )
	(symbol "C_22u_0603_1" (pin_numbers hide) (pin_names hide) (in_bom yes) (on_board yes)
      (property "Reference" "C" (at 20.32 -5.08 0)
        (effects (font (size 1.27 1.27) (thickness 0.15)) (justify left bottom))
      )
      (property "Value" "C_22u_0603" (at 20.32 -10.16 0)
        (effects (font (size 1.27 1.27) (thickness 0.15)) (justify left bottom) hide)
      )
      (property "Footprint" "antmicro-footprints:C_0603_1608Metric" (at 20.32 -12.7 0)
        (effects (font (size 1.27 1.27) (thickness 0.15)) (justify left bottom) hide)
      )
      (property "Datasheet" "https://www.murata.com/products/productdetail?partno=GRM188R60J226MEA0%23" (at 20.32 -15.24 0)
        (effects (font (size 1.27 1.27) (thickness 0.15)) (justify left bottom) hide)
      )
      (property "MPN" "GRM188R60J226MEA0D" (at 20.32 -17.78 0)
        (effects (font (size 1.27 1.27) (thickness 0.15)) (justify left bottom) hide)
      )
      (property "Manufacturer" "Murata" (at 20.32 -20.32 0)
        (effects (font (size 1.27 1.27) (thickness 0.15)) (justify left bottom) hide)
      )
      (property "License" "Apache-2.0" (at 20.32 -22.86 0)
        (effects (font (size 1.27 1.27) (thickness 0.15)) (justify left bottom) hide)
      )
      (property "Author" "Antmicro" (at 20.32 -25.4 0)
        (effects (font (size 1.27 1.27) (thickness 0.15)) (justify left bottom) hide)
      )
      (property "Val" "22u" (at 20.32 -7.62 0)
        (effects (font (size 1.27 1.27) (thickness 0.15)) (justify left bottom))
      )
      (property "Voltage" "" (at 20.32 -27.94 0)
        (effects (font (size 1.27 1.27)) (justify left bottom) hide)
      )
      (property "Dielectric" "" (at 20.32 -30.48 0)
        (effects (font (size 1.27 1.27)) (justify left bottom) hide)
      )
      (property "ki_keywords" "0603, SMT, CAPACITOR, PASSIVE, CERAMIC, MLCC" (at 0 0 0)
        (effects (font (size 1.27 1.27)) hide)
      )
      (property "ki_description" "SMD Multilayer Ceramic Capacitor, 22 µF, 6.3 V, 0603 [1608 Metric], ± 20%, X5R, GRM Series" (at 0 0 0)
        (effects (font (size 1.27 1.27)) hide)
      )
      (symbol "C_22u_0603_1_0_1"
        (polyline
          (pts
            (xy 2.032 -1.524)
            (xy 2.032 1.524)
          )
          (stroke (width 0.3048) (type default))
          (fill (type none))
        )
        (polyline
          (pts
            (xy 3.048 -1.524)
            (xy 3.048 1.524)
          )
          (stroke (width 0.3302) (type default))
          (fill (type none))
        )
      )
      (symbol "C_22u_0603_1_1_1"
        (pin passive line (at 0 0 0) (length 2.032)
          (name "~" (effects (font (size 1.27 1.27))))
          (number "1" (effects (font (size 1.27 1.27))))
        )
        (pin passive line (at 5.08 0 180) (length 2.032)
          (name "~" (effects (font (size 1.27 1.27))))
          (number "2" (effects (font (size 1.27 1.27))))
        )
      )
    )
	(symbol "C_22u_0603_2" (pin_numbers hide) (pin_names hide) (in_bom yes) (on_board yes)
      (property "Reference" "C" (at 20.32 -5.08 0)
        (effects (font (size 1.27 1.27) (thickness 0.15)) (justify left bottom))
      )
      (property "Value" "C_22u_0603" (at 20.32 -10.16 0)
        (effects (font (size 1.27 1.27) (thickness 0.15)) (justify left bottom) hide)
      )
      (property "Footprint" "antmicro-footprints:C_0603_1608Metric" (at 20.32 -12.7 0)
        (effects (font (size 1.27 1.27) (thickness 0.15)) (justify left bottom) hide)
      )
      (property "Datasheet" "https://www.murata.com/products/productdetail?partno=GRM188R60J226MEA0%23" (at 20.32 -15.24 0)
        (effects (font (size 1.27 1.27) (thickness 0.15)) (justify left bottom) hide)
      )
      (property "MPN" "GRM188R60J226MEA0D" (at 20.32 -17.78 0)
        (effects (font (size 1.27 1.27) (thickness 0.15)) (justify left bottom) hide)
      )
      (property "Manufacturer" "Murata" (at 20.32 -20.32 0)
        (effects (font (size 1.27 1.27) (thickness 0.15)) (justify left bottom) hide)
      )
      (property "License" "Apache-2.0" (at 20.32 -22.86 0)
        (effects (font (size 1.27 1.27) (thickness 0.15)) (justify left bottom) hide)
      )
      (property "Author" "Antmicro" (at 20.32 -25.4 0)
        (effects (font (size 1.27 1.27) (thickness 0.15)) (justify left bottom) hide)
      )
      (property "Val" "22u" (at 20.32 -7.62 0)
        (effects (font (size 1.27 1.27) (thickness 0.15)) (justify left bottom))
      )
      (property "Voltage" "" (at 20.32 -27.94 0)
        (effects (font (size 1.27 1.27)) (justify left bottom) hide)
      )
      (property "Dielectric" "" (at 20.32 -30.48 0)
        (effects (font (size 1.27 1.27)) (justify left bottom) hide)
      )
      (property "ki_keywords" "0603, SMT, CAPACITOR, PASSIVE, CERAMIC, MLCC" (at 0 0 0)
        (effects (font (size 1.27 1.27)) hide)
      )
      (property "ki_description" "SMD Multilayer Ceramic Capacitor, 22 µF, 6.3 V, 0603 [1608 Metric], ± 20%, X5R, GRM Series" (at 0 0 0)
        (effects (font (size 1.27 1.27)) hide)
      )
      (symbol "C_22u_0603_2_0_1"
        (polyline
          (pts
            (xy 2.032 -1.524)
            (xy 2.032 1.524)
          )
          (stroke (width 0.3048) (type default))
          (fill (type none))
        )
        (polyline
          (pts
            (xy 3.048 -1.524)
            (xy 3.048 1.524)
          )
          (stroke (width 0.3302) (type default))
          (fill (type none))
        )
      )
      (symbol "C_22u_0603_2_1_1"
        (pin passive line (at 0 0 0) (length 2.032)
          (name "~" (effects (font (size 1.27 1.27))))
          (number "1" (effects (font (size 1.27 1.27))))
        )
        (pin passive line (at 5.08 0 180) (length 2.032)
          (name "~" (effects (font (size 1.27 1.27))))
          (number "2" (effects (font (size 1.27 1.27))))
        )
      )
    )
	(symbol "C_4u7_0402_1" (pin_numbers hide) (pin_names hide) (in_bom yes) (on_board yes)
      (property "Reference" "C" (at 20.32 -5.08 0)
        (effects (font (size 1.27 1.27) (thickness 0.15)) (justify left bottom))
      )
      (property "Value" "C_4u7_0402" (at 20.32 -10.16 0)
        (effects (font (size 1.27 1.27) (thickness 0.15)) (justify left bottom) hide)
      )
      (property "Footprint" "antmicro-footprints:C_0402_1005Metric" (at 20.32 -12.7 0)
        (effects (font (size 1.27 1.27) (thickness 0.15)) (justify left bottom) hide)
      )
      (property "Datasheet" "https://www.murata.com/products/productdetail?partno=GRM155R61A475MEAA%23" (at 20.32 -15.24 0)
        (effects (font (size 1.27 1.27) (thickness 0.15)) (justify left bottom) hide)
      )
      (property "MPN" "GRM155R61A475MEAAD" (at 20.32 -17.78 0)
        (effects (font (size 1.27 1.27) (thickness 0.15)) (justify left bottom) hide)
      )
      (property "Manufacturer" "Murata" (at 20.32 -20.32 0)
        (effects (font (size 1.27 1.27) (thickness 0.15)) (justify left bottom) hide)
      )
      (property "License" "Apache-2.0" (at 20.32 -22.86 0)
        (effects (font (size 1.27 1.27) (thickness 0.15)) (justify left bottom) hide)
      )
      (property "Author" "Antmicro" (at 20.32 -25.4 0)
        (effects (font (size 1.27 1.27) (thickness 0.15)) (justify left bottom) hide)
      )
      (property "Val" "4u7" (at 20.32 -7.62 0)
        (effects (font (size 1.27 1.27) (thickness 0.15)) (justify left bottom))
      )
      (property "Voltage" "" (at 20.32 -27.94 0)
        (effects (font (size 1.27 1.27)) (justify left bottom) hide)
      )
      (property "Dielectric" "" (at 20.32 -30.48 0)
        (effects (font (size 1.27 1.27)) (justify left bottom) hide)
      )
      (property "ki_keywords" "0402, SMT, CAPACITOR, PASSIVE" (at 0 0 0)
        (effects (font (size 1.27 1.27)) hide)
      )
      (property "ki_description" "SMD Multilayer Ceramic Capacitor, 4.7 µF, 10 V, 0402 [1005 Metric], ± 20%, X5R, GRM Series" (at 0 0 0)
        (effects (font (size 1.27 1.27)) hide)
      )
      (symbol "C_4u7_0402_1_0_1"
        (polyline
          (pts
            (xy 2.032 -1.524)
            (xy 2.032 1.524)
          )
          (stroke (width 0.3048) (type default))
          (fill (type none))
        )
        (polyline
          (pts
            (xy 3.048 -1.524)
            (xy 3.048 1.524)
          )
          (stroke (width 0.3302) (type default))
          (fill (type none))
        )
      )
      (symbol "C_4u7_0402_1_1_1"
        (pin passive line (at 0 0 0) (length 2.032)
          (name "~" (effects (font (size 1.27 1.27))))
          (number "1" (effects (font (size 1.27 1.27))))
        )
        (pin passive line (at 5.08 0 180) (length 2.032)
          (name "~" (effects (font (size 1.27 1.27))))
          (number "2" (effects (font (size 1.27 1.27))))
        )
      )
    )
	(symbol "C_4u7_0402_2" (pin_numbers hide) (pin_names hide) (in_bom yes) (on_board yes)
      (property "Reference" "C" (at 20.32 -5.08 0)
        (effects (font (size 1.27 1.27) (thickness 0.15)) (justify left bottom))
      )
      (property "Value" "C_4u7_0402" (at 20.32 -10.16 0)
        (effects (font (size 1.27 1.27) (thickness 0.15)) (justify left bottom) hide)
      )
      (property "Footprint" "antmicro-footprints:C_0402_1005Metric" (at 20.32 -12.7 0)
        (effects (font (size 1.27 1.27) (thickness 0.15)) (justify left bottom) hide)
      )
      (property "Datasheet" "https://www.murata.com/products/productdetail?partno=GRM155R61A475MEAA%23" (at 20.32 -15.24 0)
        (effects (font (size 1.27 1.27) (thickness 0.15)) (justify left bottom) hide)
      )
      (property "MPN" "GRM155R61A475MEAAD" (at 20.32 -17.78 0)
        (effects (font (size 1.27 1.27) (thickness 0.15)) (justify left bottom) hide)
      )
      (property "Manufacturer" "Murata" (at 20.32 -20.32 0)
        (effects (font (size 1.27 1.27) (thickness 0.15)) (justify left bottom) hide)
      )
      (property "License" "Apache-2.0" (at 20.32 -22.86 0)
        (effects (font (size 1.27 1.27) (thickness 0.15)) (justify left bottom) hide)
      )
      (property "Author" "Antmicro" (at 20.32 -25.4 0)
        (effects (font (size 1.27 1.27) (thickness 0.15)) (justify left bottom) hide)
      )
      (property "Val" "4u7" (at 20.32 -7.62 0)
        (effects (font (size 1.27 1.27) (thickness 0.15)) (justify left bottom))
      )
      (property "Voltage" "" (at 20.32 -27.94 0)
        (effects (font (size 1.27 1.27)) (justify left bottom) hide)
      )
      (property "Dielectric" "" (at 20.32 -30.48 0)
        (effects (font (size 1.27 1.27)) (justify left bottom) hide)
      )
      (property "ki_keywords" "0402, SMT, CAPACITOR, PASSIVE" (at 0 0 0)
        (effects (font (size 1.27 1.27)) hide)
      )
      (property "ki_description" "SMD Multilayer Ceramic Capacitor, 4.7 µF, 10 V, 0402 [1005 Metric], ± 20%, X5R, GRM Series" (at 0 0 0)
        (effects (font (size 1.27 1.27)) hide)
      )
      (symbol "C_4u7_0402_2_0_1"
        (polyline
          (pts
            (xy 2.032 -1.524)
            (xy 2.032 1.524)
          )
          (stroke (width 0.3048) (type default))
          (fill (type none))
        )
        (polyline
          (pts
            (xy 3.048 -1.524)
            (xy 3.048 1.524)
          )
          (stroke (width 0.3302) (type default))
          (fill (type none))
        )
      )
      (symbol "C_4u7_0402_2_1_1"
        (pin passive line (at 0 0 0) (length 2.032)
          (name "~" (effects (font (size 1.27 1.27))))
          (number "1" (effects (font (size 1.27 1.27))))
        )
        (pin passive line (at 5.08 0 180) (length 2.032)
          (name "~" (effects (font (size 1.27 1.27))))
          (number "2" (effects (font (size 1.27 1.27))))
        )
      )
    )
	(symbol "C_4u7_0402_3" (pin_numbers hide) (pin_names hide) (in_bom yes) (on_board yes)
      (property "Reference" "C" (at 20.32 -5.08 0)
        (effects (font (size 1.27 1.27) (thickness 0.15)) (justify left bottom))
      )
      (property "Value" "C_4u7_0402" (at 20.32 -10.16 0)
        (effects (font (size 1.27 1.27) (thickness 0.15)) (justify left bottom) hide)
      )
      (property "Footprint" "antmicro-footprints:C_0402_1005Metric" (at 20.32 -12.7 0)
        (effects (font (size 1.27 1.27) (thickness 0.15)) (justify left bottom) hide)
      )
      (property "Datasheet" "https://www.murata.com/products/productdetail?partno=GRM155R61A475MEAA%23" (at 20.32 -15.24 0)
        (effects (font (size 1.27 1.27) (thickness 0.15)) (justify left bottom) hide)
      )
      (property "MPN" "GRM155R61A475MEAAD" (at 20.32 -17.78 0)
        (effects (font (size 1.27 1.27) (thickness 0.15)) (justify left bottom) hide)
      )
      (property "Manufacturer" "Murata" (at 20.32 -20.32 0)
        (effects (font (size 1.27 1.27) (thickness 0.15)) (justify left bottom) hide)
      )
      (property "License" "Apache-2.0" (at 20.32 -22.86 0)
        (effects (font (size 1.27 1.27) (thickness 0.15)) (justify left bottom) hide)
      )
      (property "Author" "Antmicro" (at 20.32 -25.4 0)
        (effects (font (size 1.27 1.27) (thickness 0.15)) (justify left bottom) hide)
      )
      (property "Val" "4u7" (at 20.32 -7.62 0)
        (effects (font (size 1.27 1.27) (thickness 0.15)) (justify left bottom))
      )
      (property "Voltage" "" (at 20.32 -27.94 0)
        (effects (font (size 1.27 1.27)) (justify left bottom) hide)
      )
      (property "Dielectric" "" (at 20.32 -30.48 0)
        (effects (font (size 1.27 1.27)) (justify left bottom) hide)
      )
      (property "ki_keywords" "0402, SMT, CAPACITOR, PASSIVE" (at 0 0 0)
        (effects (font (size 1.27 1.27)) hide)
      )
      (property "ki_description" "SMD Multilayer Ceramic Capacitor, 4.7 µF, 10 V, 0402 [1005 Metric], ± 20%, X5R, GRM Series" (at 0 0 0)
        (effects (font (size 1.27 1.27)) hide)
      )
      (symbol "C_4u7_0402_3_0_1"
        (polyline
          (pts
            (xy 2.032 -1.524)
            (xy 2.032 1.524)
          )
          (stroke (width 0.3048) (type default))
          (fill (type none))
        )
        (polyline
          (pts
            (xy 3.048 -1.524)
            (xy 3.048 1.524)
          )
          (stroke (width 0.3302) (type default))
          (fill (type none))
        )
      )
      (symbol "C_4u7_0402_3_1_1"
        (pin passive line (at 0 0 0) (length 2.032)
          (name "~" (effects (font (size 1.27 1.27))))
          (number "1" (effects (font (size 1.27 1.27))))
        )
        (pin passive line (at 5.08 0 180) (length 2.032)
          (name "~" (effects (font (size 1.27 1.27))))
          (number "2" (effects (font (size 1.27 1.27))))
        )
      )
    )
	(symbol "C_4u7_0402_4" (pin_numbers hide) (pin_names hide) (in_bom yes) (on_board yes)
      (property "Reference" "C" (at 20.32 -5.08 0)
        (effects (font (size 1.27 1.27) (thickness 0.15)) (justify left bottom))
      )
      (property "Value" "C_4u7_0402" (at 20.32 -10.16 0)
        (effects (font (size 1.27 1.27) (thickness 0.15)) (justify left bottom) hide)
      )
      (property "Footprint" "antmicro-footprints:C_0402_1005Metric" (at 20.32 -12.7 0)
        (effects (font (size 1.27 1.27) (thickness 0.15)) (justify left bottom) hide)
      )
      (property "Datasheet" "https://www.murata.com/products/productdetail?partno=GRM155R61A475MEAA%23" (at 20.32 -15.24 0)
        (effects (font (size 1.27 1.27) (thickness 0.15)) (justify left bottom) hide)
      )
      (property "MPN" "GRM155R61A475MEAAD" (at 20.32 -17.78 0)
        (effects (font (size 1.27 1.27) (thickness 0.15)) (justify left bottom) hide)
      )
      (property "Manufacturer" "Murata" (at 20.32 -20.32 0)
        (effects (font (size 1.27 1.27) (thickness 0.15)) (justify left bottom) hide)
      )
      (property "License" "Apache-2.0" (at 20.32 -22.86 0)
        (effects (font (size 1.27 1.27) (thickness 0.15)) (justify left bottom) hide)
      )
      (property "Author" "Antmicro" (at 20.32 -25.4 0)
        (effects (font (size 1.27 1.27) (thickness 0.15)) (justify left bottom) hide)
      )
      (property "Val" "4u7" (at 20.32 -7.62 0)
        (effects (font (size 1.27 1.27) (thickness 0.15)) (justify left bottom))
      )
      (property "Voltage" "" (at 20.32 -27.94 0)
        (effects (font (size 1.27 1.27)) (justify left bottom) hide)
      )
      (property "Dielectric" "" (at 20.32 -30.48 0)
        (effects (font (size 1.27 1.27)) (justify left bottom) hide)
      )
      (property "ki_keywords" "0402, SMT, CAPACITOR, PASSIVE" (at 0 0 0)
        (effects (font (size 1.27 1.27)) hide)
      )
      (property "ki_description" "SMD Multilayer Ceramic Capacitor, 4.7 µF, 10 V, 0402 [1005 Metric], ± 20%, X5R, GRM Series" (at 0 0 0)
        (effects (font (size 1.27 1.27)) hide)
      )
      (symbol "C_4u7_0402_4_0_1"
        (polyline
          (pts
            (xy 2.032 -1.524)
            (xy 2.032 1.524)
          )
          (stroke (width 0.3048) (type default))
          (fill (type none))
        )
        (polyline
          (pts
            (xy 3.048 -1.524)
            (xy 3.048 1.524)
          )
          (stroke (width 0.3302) (type default))
          (fill (type none))
        )
      )
      (symbol "C_4u7_0402_4_1_1"
        (pin passive line (at 0 0 0) (length 2.032)
          (name "~" (effects (font (size 1.27 1.27))))
          (number "1" (effects (font (size 1.27 1.27))))
        )
        (pin passive line (at 5.08 0 180) (length 2.032)
          (name "~" (effects (font (size 1.27 1.27))))
          (number "2" (effects (font (size 1.27 1.27))))
        )
      )
    )
	(symbol "FB_600Z_0.5A_Murata-BLM18AG_0603_1" (pin_numbers hide) (pin_names hide) (in_bom yes) (on_board yes)
      (property "Reference" "FB" (at 15.24 0 0)
        (effects (font (size 1.27 1.27) (thickness 0.15)) (justify left bottom))
      )
      (property "Value" "FB_600Z_0.5A_Murata-BLM18AG_0603" (at 15.24 -2.54 0)
        (effects (font (size 1.27 1.27) (thickness 0.15)) (justify left bottom) hide)
      )
      (property "Footprint" "antmicro-footprints:FB_0603_1608Metric" (at 15.24 -7.62 0)
        (effects (font (size 1.27 1.27) (thickness 0.15)) (justify left bottom) hide)
      )
      (property "Datasheet" "https://www.murata.com/en-us/products/productdata/8796738650142/ENFA0003.pdf" (at 15.24 -10.16 0)
        (effects (font (size 1.27 1.27) (thickness 0.15)) (justify left bottom) hide)
      )
      (property "Val" "600Z/0.5A" (at 15.24 -5.08 0)
        (effects (font (size 1.27 1.27)) (justify left bottom))
      )
      (property "MPN" "BLM18AG601SN1D" (at 15.24 -12.7 0)
        (effects (font (size 1.27 1.27) (thickness 0.15)) (justify left bottom) hide)
      )
      (property "Manufacturer" "Murata" (at 15.24 -15.24 0)
        (effects (font (size 1.27 1.27) (thickness 0.15)) (justify left bottom) hide)
      )
      (property "Current" "" (at 20.32 -22.86 0)
        (effects (font (size 1.27 1.27) (thickness 0.15)) (justify left bottom) hide)
      )
      (property "Author" "Antmicro" (at 15.24 -17.78 0)
        (effects (font (size 1.27 1.27) (thickness 0.15)) (justify left bottom) hide)
      )
      (property "License" "Apache-2.0" (at 15.24 -20.32 0)
        (effects (font (size 1.27 1.27) (thickness 0.15)) (justify left bottom) hide)
      )
      (property "ki_keywords" "0603, SMT, FERRITE BEAD, PASSIVE" (at 0 0 0)
        (effects (font (size 1.27 1.27)) hide)
      )
      (property "ki_description" "Ferrite Bead, 0603 [1608 Metric], 600 ohm, 500 mA, BLM18A, 0.38 ohm, ± 25%, General use" (at 0 0 0)
        (effects (font (size 1.27 1.27)) hide)
      )
      (symbol "FB_600Z_0.5A_Murata-BLM18AG_0603_1_0_1"
        (polyline
          (pts
            (xy 1.651 0)
            (xy 1.2446 0)
          )
          (stroke (width 0) (type default))
          (fill (type none))
        )
        (polyline
          (pts
            (xy 3.81 0)
            (xy 3.3274 0)
          )
          (stroke (width 0) (type default))
          (fill (type none))
        )
        (polyline
          (pts
            (xy 2.2606 -1.8288)
            (xy 1.0414 -1.1176)
            (xy 2.7432 1.8288)
            (xy 3.9624 1.1176)
            (xy 2.2606 -1.8288)
          )
          (stroke (width 0) (type default))
          (fill (type none))
        )
      )
      (symbol "FB_600Z_0.5A_Murata-BLM18AG_0603_1_1_1"
        (pin passive line (at 0 0 0) (length 1.27)
          (name "~" (effects (font (size 1.27 1.27))))
          (number "1" (effects (font (size 1.27 1.27))))
        )
        (pin passive line (at 5.08 0 180) (length 1.27)
          (name "~" (effects (font (size 1.27 1.27))))
          (number "2" (effects (font (size 1.27 1.27))))
        )
      )
    )
	(symbol "FB_600Z_0.5A_Murata-BLM18AG_0603_2" (pin_numbers hide) (pin_names hide) (in_bom yes) (on_board yes)
      (property "Reference" "FB" (at 15.24 0 0)
        (effects (font (size 1.27 1.27) (thickness 0.15)) (justify left bottom))
      )
      (property "Value" "FB_600Z_0.5A_Murata-BLM18AG_0603" (at 15.24 -2.54 0)
        (effects (font (size 1.27 1.27) (thickness 0.15)) (justify left bottom) hide)
      )
      (property "Footprint" "antmicro-footprints:FB_0603_1608Metric" (at 15.24 -7.62 0)
        (effects (font (size 1.27 1.27) (thickness 0.15)) (justify left bottom) hide)
      )
      (property "Datasheet" "https://www.murata.com/en-us/products/productdata/8796738650142/ENFA0003.pdf" (at 15.24 -10.16 0)
        (effects (font (size 1.27 1.27) (thickness 0.15)) (justify left bottom) hide)
      )
      (property "Val" "600Z/0.5A" (at 15.24 -5.08 0)
        (effects (font (size 1.27 1.27)) (justify left bottom))
      )
      (property "MPN" "BLM18AG601SN1D" (at 15.24 -12.7 0)
        (effects (font (size 1.27 1.27) (thickness 0.15)) (justify left bottom) hide)
      )
      (property "Manufacturer" "Murata" (at 15.24 -15.24 0)
        (effects (font (size 1.27 1.27) (thickness 0.15)) (justify left bottom) hide)
      )
      (property "Current" "" (at 20.32 -22.86 0)
        (effects (font (size 1.27 1.27) (thickness 0.15)) (justify left bottom) hide)
      )
      (property "Author" "Antmicro" (at 15.24 -17.78 0)
        (effects (font (size 1.27 1.27) (thickness 0.15)) (justify left bottom) hide)
      )
      (property "License" "Apache-2.0" (at 15.24 -20.32 0)
        (effects (font (size 1.27 1.27) (thickness 0.15)) (justify left bottom) hide)
      )
      (property "ki_keywords" "0603, SMT, FERRITE BEAD, PASSIVE" (at 0 0 0)
        (effects (font (size 1.27 1.27)) hide)
      )
      (property "ki_description" "Ferrite Bead, 0603 [1608 Metric], 600 ohm, 500 mA, BLM18A, 0.38 ohm, ± 25%, General use" (at 0 0 0)
        (effects (font (size 1.27 1.27)) hide)
      )
      (symbol "FB_600Z_0.5A_Murata-BLM18AG_0603_2_0_1"
        (polyline
          (pts
            (xy 1.651 0)
            (xy 1.2446 0)
          )
          (stroke (width 0) (type default))
          (fill (type none))
        )
        (polyline
          (pts
            (xy 3.81 0)
            (xy 3.3274 0)
          )
          (stroke (width 0) (type default))
          (fill (type none))
        )
        (polyline
          (pts
            (xy 2.2606 -1.8288)
            (xy 1.0414 -1.1176)
            (xy 2.7432 1.8288)
            (xy 3.9624 1.1176)
            (xy 2.2606 -1.8288)
          )
          (stroke (width 0) (type default))
          (fill (type none))
        )
      )
      (symbol "FB_600Z_0.5A_Murata-BLM18AG_0603_2_1_1"
        (pin passive line (at 0 0 0) (length 1.27)
          (name "~" (effects (font (size 1.27 1.27))))
          (number "1" (effects (font (size 1.27 1.27))))
        )
        (pin passive line (at 5.08 0 180) (length 1.27)
          (name "~" (effects (font (size 1.27 1.27))))
          (number "2" (effects (font (size 1.27 1.27))))
        )
      )
    )
	(symbol "JST_SH_1x4_BM04B-SRSS-TB-LF-SN_1" (in_bom yes) (on_board yes)
      (property "Reference" "J" (at 20.32 -5.08 0)
        (effects (font (size 1.27 1.27) (thickness 0.15)) (justify left bottom))
      )
      (property "Value" "JST_SH_1x4_BM04B-SRSS-TB-LF-SN" (at 20.32 -7.62 0)
        (effects (font (size 1.27 1.27) (thickness 0.15)) (justify left bottom) hide)
      )
      (property "Footprint" "antmicro-footprints:Conn_JST_SH_1x4_BM04B-SRSS-TB-LF-SN" (at 20.32 -10.16 0)
        (effects (font (size 1.27 1.27) (thickness 0.15)) (justify left bottom) hide)
      )
      (property "Datasheet" "https://www.jst-mfg.com/product/pdf/eng/eSH.pdf" (at 20.32 -12.7 0)
        (effects (font (size 1.27 1.27) (thickness 0.15)) (justify left bottom) hide)
      )
      (property "MPN" "BM04B-SRSS-TB(LF)(SN) " (at 20.32 -15.24 0)
        (effects (font (size 1.27 1.27) (thickness 0.15)) (justify left bottom))
      )
      (property "Manufacturer" "JST Automotive Connectors" (at 20.32 -17.78 0)
        (effects (font (size 1.27 1.27) (thickness 0.15)) (justify left bottom) hide)
      )
      (property "Author" "Antmicro" (at 20.32 -20.32 0)
        (effects (font (size 1.27 1.27) (thickness 0.15)) (justify left bottom) hide)
      )
      (property "License" "Apache-2.0" (at 20.32 -22.86 0)
        (effects (font (size 1.27 1.27) (thickness 0.15)) (justify left bottom) hide)
      )
      (property "ki_keywords" "VERTICAL, SMT, WIRE-BOARD, CONNECTOR" (at 0 0 0)
        (effects (font (size 1.27 1.27)) hide)
      )
      (property "ki_description" "Pin Header, Top Entry, Wire-to-Board, 1 mm, 1 Rows, 4 Contacts, Surface Mount, SR" (at 0 0 0)
        (effects (font (size 1.27 1.27)) hide)
      )
      (symbol "JST_SH_1x4_BM04B-SRSS-TB-LF-SN_1_1_1"
        (rectangle (start 2.54 -10.033) (end 3.81 -10.287)
          (stroke (width 0.254) (type default))
          (fill (type background))
        )
        (rectangle (start 2.54 -7.493) (end 3.81 -7.747)
          (stroke (width 0.254) (type default))
          (fill (type background))
        )
        (rectangle (start 2.54 -4.953) (end 3.81 -5.207)
          (stroke (width 0.254) (type default))
          (fill (type background))
        )
        (rectangle (start 2.54 -2.413) (end 3.81 -2.667)
          (stroke (width 0.254) (type default))
          (fill (type background))
        )
        (rectangle (start 2.54 0.127) (end 3.81 -0.127)
          (stroke (width 0.254) (type default))
          (fill (type background))
        )
        (rectangle (start 2.54 2.54) (end 5.08 -12.7)
          (stroke (width 0.254) (type default))
          (fill (type background))
        )
        (pin passive line (at 0 0 0) (length 2.54)
          (name "~" (effects (font (size 1.27 1.27))))
          (number "1" (effects (font (size 1.27 1.27))))
        )
        (pin passive line (at 0 -2.54 0) (length 2.54)
          (name "~" (effects (font (size 1.27 1.27))))
          (number "2" (effects (font (size 1.27 1.27))))
        )
        (pin passive line (at 0 -5.08 0) (length 2.54)
          (name "~" (effects (font (size 1.27 1.27))))
          (number "3" (effects (font (size 1.27 1.27))))
        )
        (pin passive line (at 0 -7.62 0) (length 2.54)
          (name "~" (effects (font (size 1.27 1.27))))
          (number "4" (effects (font (size 1.27 1.27))))
        )
        (pin passive line (at 0 -10.16 0) (length 2.54)
          (name "~" (effects (font (size 1.27 1.27))))
          (number "MP" (effects (font (size 1.27 1.27))))
        )
      )
    )
	(symbol "LED_G_0603_LG_L29K-G2J1-24-Z_1" (pin_numbers hide) (pin_names hide) (in_bom yes) (on_board yes)
      (property "Reference" "D" (at 20.32 -2.54 0)
        (effects (font (size 1.27 1.27) (thickness 0.15)) (justify left bottom))
      )
      (property "Value" "LED_G_0603_LG_L29K-G2J1-24-Z" (at 20.32 -7.62 0)
        (effects (font (size 1.27 1.27) (thickness 0.15)) (justify left bottom) hide)
      )
      (property "Footprint" "antmicro-footprints:LED_0603_1608Metric_G" (at 20.32 -10.16 0)
        (effects (font (size 1.27 1.27) (thickness 0.15)) (justify left bottom) hide)
      )
      (property "Datasheet" "https://look.ams-osram.com/m/19ee86b3ae0ee95b/original/LG-L29K.pdf" (at 20.32 -12.7 0)
        (effects (font (size 1.27 1.27) (thickness 0.15)) (justify left bottom) hide)
      )
      (property "MPN" "LG L29K-G2J1-24-Z" (at 20.32 -15.24 0)
        (effects (font (size 1.27 1.27) (thickness 0.15)) (justify left bottom) hide)
      )
      (property "Manufacturer" "OSRAM" (at 20.32 -17.78 0)
        (effects (font (size 1.27 1.27) (thickness 0.15)) (justify left bottom) hide)
      )
      (property "Color" "Green" (at 20.32 -5.08 0)
        (effects (font (size 1.27 1.27)) (justify left bottom))
      )
      (property "Author" "Antmicro" (at 20.32 -20.32 0)
        (effects (font (size 1.27 1.27) (thickness 0.15)) (justify left bottom) hide)
      )
      (property "License" "Apache-2.0" (at 20.32 -22.86 0)
        (effects (font (size 1.27 1.27) (thickness 0.15)) (justify left bottom) hide)
      )
      (property "ki_keywords" "SMT, DIODE, SEMICONDUCTOR, LED" (at 0 0 0)
        (effects (font (size 1.27 1.27)) hide)
      )
      (property "ki_description" "LED, Green, SMD, 0603, 20 mA, 1.7 V, 570 nm" (at 0 0 0)
        (effects (font (size 1.27 1.27)) hide)
      )
      (symbol "LED_G_0603_LG_L29K-G2J1-24-Z_1_0_1"
        (polyline
          (pts
            (xy 1.905 0)
            (xy 0.635 0)
          )
          (stroke (width 0) (type default))
          (fill (type none))
        )
        (polyline
          (pts
            (xy 4.445 0)
            (xy 3.175 0)
          )
          (stroke (width 0) (type default))
          (fill (type none))
        )
      )
      (symbol "LED_G_0603_LG_L29K-G2J1-24-Z_1_1_1"
        (polyline
          (pts
            (xy 1.778 1.016)
            (xy 1.778 -1.016)
          )
          (stroke (width 0.254) (type default))
          (fill (type none))
        )
        (polyline
          (pts
            (xy 3.302 1.016)
            (xy 3.302 -1.016)
            (xy 1.778 0)
            (xy 3.302 1.016)
          )
          (stroke (width 0.254) (type default))
          (fill (type outline))
        )
        (polyline
          (pts
            (xy 1.143 2.286)
            (xy 1.143 1.778)
            (xy 1.143 2.286)
            (xy 1.651 2.286)
            (xy 1.143 2.286)
            (xy 2.159 1.27)
          )
          (stroke (width 0.254) (type default))
          (fill (type none))
        )
        (polyline
          (pts
            (xy 2.159 2.54)
            (xy 2.159 2.032)
            (xy 2.159 2.54)
            (xy 2.667 2.54)
            (xy 2.159 2.54)
            (xy 3.048 1.651)
          )
          (stroke (width 0.254) (type default))
          (fill (type none))
        )
        (pin passive line (at 0 0 0) (length 0.635)
          (name "C" (effects (font (size 1.27 1.27))))
          (number "1" (effects (font (size 1.27 1.27))))
        )
        (pin passive line (at 5.08 0 180) (length 0.635)
          (name "A" (effects (font (size 1.27 1.27))))
          (number "2" (effects (font (size 1.27 1.27))))
        )
      )
    )
	(symbol "LED_G_0603_LG_L29K-G2J1-24-Z_2" (pin_numbers hide) (pin_names hide) (in_bom yes) (on_board yes)
      (property "Reference" "D" (at 20.32 -2.54 0)
        (effects (font (size 1.27 1.27) (thickness 0.15)) (justify left bottom))
      )
      (property "Value" "LED_G_0603_LG_L29K-G2J1-24-Z" (at 20.32 -7.62 0)
        (effects (font (size 1.27 1.27) (thickness 0.15)) (justify left bottom) hide)
      )
      (property "Footprint" "antmicro-footprints:LED_0603_1608Metric_G" (at 20.32 -10.16 0)
        (effects (font (size 1.27 1.27) (thickness 0.15)) (justify left bottom) hide)
      )
      (property "Datasheet" "https://look.ams-osram.com/m/19ee86b3ae0ee95b/original/LG-L29K.pdf" (at 20.32 -12.7 0)
        (effects (font (size 1.27 1.27) (thickness 0.15)) (justify left bottom) hide)
      )
      (property "MPN" "LG L29K-G2J1-24-Z" (at 20.32 -15.24 0)
        (effects (font (size 1.27 1.27) (thickness 0.15)) (justify left bottom) hide)
      )
      (property "Manufacturer" "OSRAM" (at 20.32 -17.78 0)
        (effects (font (size 1.27 1.27) (thickness 0.15)) (justify left bottom) hide)
      )
      (property "Color" "Green" (at 20.32 -5.08 0)
        (effects (font (size 1.27 1.27)) (justify left bottom))
      )
      (property "Author" "Antmicro" (at 20.32 -20.32 0)
        (effects (font (size 1.27 1.27) (thickness 0.15)) (justify left bottom) hide)
      )
      (property "License" "Apache-2.0" (at 20.32 -22.86 0)
        (effects (font (size 1.27 1.27) (thickness 0.15)) (justify left bottom) hide)
      )
      (property "ki_keywords" "SMT, DIODE, SEMICONDUCTOR, LED" (at 0 0 0)
        (effects (font (size 1.27 1.27)) hide)
      )
      (property "ki_description" "LED, Green, SMD, 0603, 20 mA, 1.7 V, 570 nm" (at 0 0 0)
        (effects (font (size 1.27 1.27)) hide)
      )
      (symbol "LED_G_0603_LG_L29K-G2J1-24-Z_2_0_1"
        (polyline
          (pts
            (xy 1.905 0)
            (xy 0.635 0)
          )
          (stroke (width 0) (type default))
          (fill (type none))
        )
        (polyline
          (pts
            (xy 4.445 0)
            (xy 3.175 0)
          )
          (stroke (width 0) (type default))
          (fill (type none))
        )
      )
      (symbol "LED_G_0603_LG_L29K-G2J1-24-Z_2_1_1"
        (polyline
          (pts
            (xy 1.778 1.016)
            (xy 1.778 -1.016)
          )
          (stroke (width 0.254) (type default))
          (fill (type none))
        )
        (polyline
          (pts
            (xy 3.302 1.016)
            (xy 3.302 -1.016)
            (xy 1.778 0)
            (xy 3.302 1.016)
          )
          (stroke (width 0.254) (type default))
          (fill (type outline))
        )
        (polyline
          (pts
            (xy 1.143 2.286)
            (xy 1.143 1.778)
            (xy 1.143 2.286)
            (xy 1.651 2.286)
            (xy 1.143 2.286)
            (xy 2.159 1.27)
          )
          (stroke (width 0.254) (type default))
          (fill (type none))
        )
        (polyline
          (pts
            (xy 2.159 2.54)
            (xy 2.159 2.032)
            (xy 2.159 2.54)
            (xy 2.667 2.54)
            (xy 2.159 2.54)
            (xy 3.048 1.651)
          )
          (stroke (width 0.254) (type default))
          (fill (type none))
        )
        (pin passive line (at 0 0 0) (length 0.635)
          (name "C" (effects (font (size 1.27 1.27))))
          (number "1" (effects (font (size 1.27 1.27))))
        )
        (pin passive line (at 5.08 0 180) (length 0.635)
          (name "A" (effects (font (size 1.27 1.27))))
          (number "2" (effects (font (size 1.27 1.27))))
        )
      )
    )
	(symbol "LED_G_0603_LG_L29K-G2J1-24-Z_3" (pin_numbers hide) (pin_names hide) (in_bom yes) (on_board yes)
      (property "Reference" "D" (at 20.32 -2.54 0)
        (effects (font (size 1.27 1.27) (thickness 0.15)) (justify left bottom))
      )
      (property "Value" "LED_G_0603_LG_L29K-G2J1-24-Z" (at 20.32 -7.62 0)
        (effects (font (size 1.27 1.27) (thickness 0.15)) (justify left bottom) hide)
      )
      (property "Footprint" "antmicro-footprints:LED_0603_1608Metric_G" (at 20.32 -10.16 0)
        (effects (font (size 1.27 1.27) (thickness 0.15)) (justify left bottom) hide)
      )
      (property "Datasheet" "https://look.ams-osram.com/m/19ee86b3ae0ee95b/original/LG-L29K.pdf" (at 20.32 -12.7 0)
        (effects (font (size 1.27 1.27) (thickness 0.15)) (justify left bottom) hide)
      )
      (property "MPN" "LG L29K-G2J1-24-Z" (at 20.32 -15.24 0)
        (effects (font (size 1.27 1.27) (thickness 0.15)) (justify left bottom) hide)
      )
      (property "Manufacturer" "OSRAM" (at 20.32 -17.78 0)
        (effects (font (size 1.27 1.27) (thickness 0.15)) (justify left bottom) hide)
      )
      (property "Color" "Green" (at 20.32 -5.08 0)
        (effects (font (size 1.27 1.27)) (justify left bottom))
      )
      (property "Author" "Antmicro" (at 20.32 -20.32 0)
        (effects (font (size 1.27 1.27) (thickness 0.15)) (justify left bottom) hide)
      )
      (property "License" "Apache-2.0" (at 20.32 -22.86 0)
        (effects (font (size 1.27 1.27) (thickness 0.15)) (justify left bottom) hide)
      )
      (property "ki_keywords" "SMT, DIODE, SEMICONDUCTOR, LED" (at 0 0 0)
        (effects (font (size 1.27 1.27)) hide)
      )
      (property "ki_description" "LED, Green, SMD, 0603, 20 mA, 1.7 V, 570 nm" (at 0 0 0)
        (effects (font (size 1.27 1.27)) hide)
      )
      (symbol "LED_G_0603_LG_L29K-G2J1-24-Z_3_0_1"
        (polyline
          (pts
            (xy 1.905 0)
            (xy 0.635 0)
          )
          (stroke (width 0) (type default))
          (fill (type none))
        )
        (polyline
          (pts
            (xy 4.445 0)
            (xy 3.175 0)
          )
          (stroke (width 0) (type default))
          (fill (type none))
        )
      )
      (symbol "LED_G_0603_LG_L29K-G2J1-24-Z_3_1_1"
        (polyline
          (pts
            (xy 1.778 1.016)
            (xy 1.778 -1.016)
          )
          (stroke (width 0.254) (type default))
          (fill (type none))
        )
        (polyline
          (pts
            (xy 3.302 1.016)
            (xy 3.302 -1.016)
            (xy 1.778 0)
            (xy 3.302 1.016)
          )
          (stroke (width 0.254) (type default))
          (fill (type outline))
        )
        (polyline
          (pts
            (xy 1.143 2.286)
            (xy 1.143 1.778)
            (xy 1.143 2.286)
            (xy 1.651 2.286)
            (xy 1.143 2.286)
            (xy 2.159 1.27)
          )
          (stroke (width 0.254) (type default))
          (fill (type none))
        )
        (polyline
          (pts
            (xy 2.159 2.54)
            (xy 2.159 2.032)
            (xy 2.159 2.54)
            (xy 2.667 2.54)
            (xy 2.159 2.54)
            (xy 3.048 1.651)
          )
          (stroke (width 0.254) (type default))
          (fill (type none))
        )
        (pin passive line (at 0 0 0) (length 0.635)
          (name "C" (effects (font (size 1.27 1.27))))
          (number "1" (effects (font (size 1.27 1.27))))
        )
        (pin passive line (at 5.08 0 180) (length 0.635)
          (name "A" (effects (font (size 1.27 1.27))))
          (number "2" (effects (font (size 1.27 1.27))))
        )
      )
    )
	(symbol "LED_G_0603_LG_L29K-G2J1-24-Z_4" (pin_numbers hide) (pin_names hide) (in_bom yes) (on_board yes)
      (property "Reference" "D" (at 20.32 -2.54 0)
        (effects (font (size 1.27 1.27) (thickness 0.15)) (justify left bottom))
      )
      (property "Value" "LED_G_0603_LG_L29K-G2J1-24-Z" (at 20.32 -7.62 0)
        (effects (font (size 1.27 1.27) (thickness 0.15)) (justify left bottom) hide)
      )
      (property "Footprint" "antmicro-footprints:LED_0603_1608Metric_G" (at 20.32 -10.16 0)
        (effects (font (size 1.27 1.27) (thickness 0.15)) (justify left bottom) hide)
      )
      (property "Datasheet" "https://look.ams-osram.com/m/19ee86b3ae0ee95b/original/LG-L29K.pdf" (at 20.32 -12.7 0)
        (effects (font (size 1.27 1.27) (thickness 0.15)) (justify left bottom) hide)
      )
      (property "MPN" "LG L29K-G2J1-24-Z" (at 20.32 -15.24 0)
        (effects (font (size 1.27 1.27) (thickness 0.15)) (justify left bottom) hide)
      )
      (property "Manufacturer" "OSRAM" (at 20.32 -17.78 0)
        (effects (font (size 1.27 1.27) (thickness 0.15)) (justify left bottom) hide)
      )
      (property "Color" "Green" (at 20.32 -5.08 0)
        (effects (font (size 1.27 1.27)) (justify left bottom))
      )
      (property "Author" "Antmicro" (at 20.32 -20.32 0)
        (effects (font (size 1.27 1.27) (thickness 0.15)) (justify left bottom) hide)
      )
      (property "License" "Apache-2.0" (at 20.32 -22.86 0)
        (effects (font (size 1.27 1.27) (thickness 0.15)) (justify left bottom) hide)
      )
      (property "ki_keywords" "SMT, DIODE, SEMICONDUCTOR, LED" (at 0 0 0)
        (effects (font (size 1.27 1.27)) hide)
      )
      (property "ki_description" "LED, Green, SMD, 0603, 20 mA, 1.7 V, 570 nm" (at 0 0 0)
        (effects (font (size 1.27 1.27)) hide)
      )
      (symbol "LED_G_0603_LG_L29K-G2J1-24-Z_4_0_1"
        (polyline
          (pts
            (xy 1.905 0)
            (xy 0.635 0)
          )
          (stroke (width 0) (type default))
          (fill (type none))
        )
        (polyline
          (pts
            (xy 4.445 0)
            (xy 3.175 0)
          )
          (stroke (width 0) (type default))
          (fill (type none))
        )
      )
      (symbol "LED_G_0603_LG_L29K-G2J1-24-Z_4_1_1"
        (polyline
          (pts
            (xy 1.778 1.016)
            (xy 1.778 -1.016)
          )
          (stroke (width 0.254) (type default))
          (fill (type none))
        )
        (polyline
          (pts
            (xy 3.302 1.016)
            (xy 3.302 -1.016)
            (xy 1.778 0)
            (xy 3.302 1.016)
          )
          (stroke (width 0.254) (type default))
          (fill (type outline))
        )
        (polyline
          (pts
            (xy 1.143 2.286)
            (xy 1.143 1.778)
            (xy 1.143 2.286)
            (xy 1.651 2.286)
            (xy 1.143 2.286)
            (xy 2.159 1.27)
          )
          (stroke (width 0.254) (type default))
          (fill (type none))
        )
        (polyline
          (pts
            (xy 2.159 2.54)
            (xy 2.159 2.032)
            (xy 2.159 2.54)
            (xy 2.667 2.54)
            (xy 2.159 2.54)
            (xy 3.048 1.651)
          )
          (stroke (width 0.254) (type default))
          (fill (type none))
        )
        (pin passive line (at 0 0 0) (length 0.635)
          (name "C" (effects (font (size 1.27 1.27))))
          (number "1" (effects (font (size 1.27 1.27))))
        )
        (pin passive line (at 5.08 0 180) (length 0.635)
          (name "A" (effects (font (size 1.27 1.27))))
          (number "2" (effects (font (size 1.27 1.27))))
        )
      )
    )
	(symbol "LED_G_0603_LG_L29K-G2J1-24-Z_5" (pin_numbers hide) (pin_names hide) (in_bom yes) (on_board yes)
      (property "Reference" "D" (at 20.32 -2.54 0)
        (effects (font (size 1.27 1.27) (thickness 0.15)) (justify left bottom))
      )
      (property "Value" "LED_G_0603_LG_L29K-G2J1-24-Z" (at 20.32 -7.62 0)
        (effects (font (size 1.27 1.27) (thickness 0.15)) (justify left bottom) hide)
      )
      (property "Footprint" "antmicro-footprints:LED_0603_1608Metric_G" (at 20.32 -10.16 0)
        (effects (font (size 1.27 1.27) (thickness 0.15)) (justify left bottom) hide)
      )
      (property "Datasheet" "https://look.ams-osram.com/m/19ee86b3ae0ee95b/original/LG-L29K.pdf" (at 20.32 -12.7 0)
        (effects (font (size 1.27 1.27) (thickness 0.15)) (justify left bottom) hide)
      )
      (property "MPN" "LG L29K-G2J1-24-Z" (at 20.32 -15.24 0)
        (effects (font (size 1.27 1.27) (thickness 0.15)) (justify left bottom) hide)
      )
      (property "Manufacturer" "OSRAM" (at 20.32 -17.78 0)
        (effects (font (size 1.27 1.27) (thickness 0.15)) (justify left bottom) hide)
      )
      (property "Color" "Green" (at 20.32 -5.08 0)
        (effects (font (size 1.27 1.27)) (justify left bottom))
      )
      (property "Author" "Antmicro" (at 20.32 -20.32 0)
        (effects (font (size 1.27 1.27) (thickness 0.15)) (justify left bottom) hide)
      )
      (property "License" "Apache-2.0" (at 20.32 -22.86 0)
        (effects (font (size 1.27 1.27) (thickness 0.15)) (justify left bottom) hide)
      )
      (property "ki_keywords" "SMT, DIODE, SEMICONDUCTOR, LED" (at 0 0 0)
        (effects (font (size 1.27 1.27)) hide)
      )
      (property "ki_description" "LED, Green, SMD, 0603, 20 mA, 1.7 V, 570 nm" (at 0 0 0)
        (effects (font (size 1.27 1.27)) hide)
      )
      (symbol "LED_G_0603_LG_L29K-G2J1-24-Z_5_0_1"
        (polyline
          (pts
            (xy 1.905 0)
            (xy 0.635 0)
          )
          (stroke (width 0) (type default))
          (fill (type none))
        )
        (polyline
          (pts
            (xy 4.445 0)
            (xy 3.175 0)
          )
          (stroke (width 0) (type default))
          (fill (type none))
        )
      )
      (symbol "LED_G_0603_LG_L29K-G2J1-24-Z_5_1_1"
        (polyline
          (pts
            (xy 1.778 1.016)
            (xy 1.778 -1.016)
          )
          (stroke (width 0.254) (type default))
          (fill (type none))
        )
        (polyline
          (pts
            (xy 3.302 1.016)
            (xy 3.302 -1.016)
            (xy 1.778 0)
            (xy 3.302 1.016)
          )
          (stroke (width 0.254) (type default))
          (fill (type outline))
        )
        (polyline
          (pts
            (xy 1.143 2.286)
            (xy 1.143 1.778)
            (xy 1.143 2.286)
            (xy 1.651 2.286)
            (xy 1.143 2.286)
            (xy 2.159 1.27)
          )
          (stroke (width 0.254) (type default))
          (fill (type none))
        )
        (polyline
          (pts
            (xy 2.159 2.54)
            (xy 2.159 2.032)
            (xy 2.159 2.54)
            (xy 2.667 2.54)
            (xy 2.159 2.54)
            (xy 3.048 1.651)
          )
          (stroke (width 0.254) (type default))
          (fill (type none))
        )
        (pin passive line (at 0 0 0) (length 0.635)
          (name "C" (effects (font (size 1.27 1.27))))
          (number "1" (effects (font (size 1.27 1.27))))
        )
        (pin passive line (at 5.08 0 180) (length 0.635)
          (name "A" (effects (font (size 1.27 1.27))))
          (number "2" (effects (font (size 1.27 1.27))))
        )
      )
    )
	(symbol "LED_G_0603_LG_L29K-G2J1-24-Z_6" (pin_numbers hide) (pin_names hide) (in_bom yes) (on_board yes)
      (property "Reference" "D" (at 20.32 -2.54 0)
        (effects (font (size 1.27 1.27) (thickness 0.15)) (justify left bottom))
      )
      (property "Value" "LED_G_0603_LG_L29K-G2J1-24-Z" (at 20.32 -7.62 0)
        (effects (font (size 1.27 1.27) (thickness 0.15)) (justify left bottom) hide)
      )
      (property "Footprint" "antmicro-footprints:LED_0603_1608Metric_G" (at 20.32 -10.16 0)
        (effects (font (size 1.27 1.27) (thickness 0.15)) (justify left bottom) hide)
      )
      (property "Datasheet" "https://look.ams-osram.com/m/19ee86b3ae0ee95b/original/LG-L29K.pdf" (at 20.32 -12.7 0)
        (effects (font (size 1.27 1.27) (thickness 0.15)) (justify left bottom) hide)
      )
      (property "MPN" "LG L29K-G2J1-24-Z" (at 20.32 -15.24 0)
        (effects (font (size 1.27 1.27) (thickness 0.15)) (justify left bottom) hide)
      )
      (property "Manufacturer" "OSRAM" (at 20.32 -17.78 0)
        (effects (font (size 1.27 1.27) (thickness 0.15)) (justify left bottom) hide)
      )
      (property "Color" "Green" (at 20.32 -5.08 0)
        (effects (font (size 1.27 1.27)) (justify left bottom))
      )
      (property "Author" "Antmicro" (at 20.32 -20.32 0)
        (effects (font (size 1.27 1.27) (thickness 0.15)) (justify left bottom) hide)
      )
      (property "License" "Apache-2.0" (at 20.32 -22.86 0)
        (effects (font (size 1.27 1.27) (thickness 0.15)) (justify left bottom) hide)
      )
      (property "ki_keywords" "SMT, DIODE, SEMICONDUCTOR, LED" (at 0 0 0)
        (effects (font (size 1.27 1.27)) hide)
      )
      (property "ki_description" "LED, Green, SMD, 0603, 20 mA, 1.7 V, 570 nm" (at 0 0 0)
        (effects (font (size 1.27 1.27)) hide)
      )
      (symbol "LED_G_0603_LG_L29K-G2J1-24-Z_6_0_1"
        (polyline
          (pts
            (xy 1.905 0)
            (xy 0.635 0)
          )
          (stroke (width 0) (type default))
          (fill (type none))
        )
        (polyline
          (pts
            (xy 4.445 0)
            (xy 3.175 0)
          )
          (stroke (width 0) (type default))
          (fill (type none))
        )
      )
      (symbol "LED_G_0603_LG_L29K-G2J1-24-Z_6_1_1"
        (polyline
          (pts
            (xy 1.778 1.016)
            (xy 1.778 -1.016)
          )
          (stroke (width 0.254) (type default))
          (fill (type none))
        )
        (polyline
          (pts
            (xy 3.302 1.016)
            (xy 3.302 -1.016)
            (xy 1.778 0)
            (xy 3.302 1.016)
          )
          (stroke (width 0.254) (type default))
          (fill (type outline))
        )
        (polyline
          (pts
            (xy 1.143 2.286)
            (xy 1.143 1.778)
            (xy 1.143 2.286)
            (xy 1.651 2.286)
            (xy 1.143 2.286)
            (xy 2.159 1.27)
          )
          (stroke (width 0.254) (type default))
          (fill (type none))
        )
        (polyline
          (pts
            (xy 2.159 2.54)
            (xy 2.159 2.032)
            (xy 2.159 2.54)
            (xy 2.667 2.54)
            (xy 2.159 2.54)
            (xy 3.048 1.651)
          )
          (stroke (width 0.254) (type default))
          (fill (type none))
        )
        (pin passive line (at 0 0 0) (length 0.635)
          (name "C" (effects (font (size 1.27 1.27))))
          (number "1" (effects (font (size 1.27 1.27))))
        )
        (pin passive line (at 5.08 0 180) (length 0.635)
          (name "A" (effects (font (size 1.27 1.27))))
          (number "2" (effects (font (size 1.27 1.27))))
        )
      )
    )
	(symbol "LED_G_0603_LG_L29K-G2J1-24-Z_7" (pin_numbers hide) (pin_names hide) (in_bom yes) (on_board yes)
      (property "Reference" "D" (at 20.32 -2.54 0)
        (effects (font (size 1.27 1.27) (thickness 0.15)) (justify left bottom))
      )
      (property "Value" "LED_G_0603_LG_L29K-G2J1-24-Z" (at 20.32 -7.62 0)
        (effects (font (size 1.27 1.27) (thickness 0.15)) (justify left bottom) hide)
      )
      (property "Footprint" "antmicro-footprints:LED_0603_1608Metric_G" (at 20.32 -10.16 0)
        (effects (font (size 1.27 1.27) (thickness 0.15)) (justify left bottom) hide)
      )
      (property "Datasheet" "https://look.ams-osram.com/m/19ee86b3ae0ee95b/original/LG-L29K.pdf" (at 20.32 -12.7 0)
        (effects (font (size 1.27 1.27) (thickness 0.15)) (justify left bottom) hide)
      )
      (property "MPN" "LG L29K-G2J1-24-Z" (at 20.32 -15.24 0)
        (effects (font (size 1.27 1.27) (thickness 0.15)) (justify left bottom) hide)
      )
      (property "Manufacturer" "OSRAM" (at 20.32 -17.78 0)
        (effects (font (size 1.27 1.27) (thickness 0.15)) (justify left bottom) hide)
      )
      (property "Color" "Green" (at 20.32 -5.08 0)
        (effects (font (size 1.27 1.27)) (justify left bottom))
      )
      (property "Author" "Antmicro" (at 20.32 -20.32 0)
        (effects (font (size 1.27 1.27) (thickness 0.15)) (justify left bottom) hide)
      )
      (property "License" "Apache-2.0" (at 20.32 -22.86 0)
        (effects (font (size 1.27 1.27) (thickness 0.15)) (justify left bottom) hide)
      )
      (property "ki_keywords" "SMT, DIODE, SEMICONDUCTOR, LED" (at 0 0 0)
        (effects (font (size 1.27 1.27)) hide)
      )
      (property "ki_description" "LED, Green, SMD, 0603, 20 mA, 1.7 V, 570 nm" (at 0 0 0)
        (effects (font (size 1.27 1.27)) hide)
      )
      (symbol "LED_G_0603_LG_L29K-G2J1-24-Z_7_0_1"
        (polyline
          (pts
            (xy 1.905 0)
            (xy 0.635 0)
          )
          (stroke (width 0) (type default))
          (fill (type none))
        )
        (polyline
          (pts
            (xy 4.445 0)
            (xy 3.175 0)
          )
          (stroke (width 0) (type default))
          (fill (type none))
        )
      )
      (symbol "LED_G_0603_LG_L29K-G2J1-24-Z_7_1_1"
        (polyline
          (pts
            (xy 1.778 1.016)
            (xy 1.778 -1.016)
          )
          (stroke (width 0.254) (type default))
          (fill (type none))
        )
        (polyline
          (pts
            (xy 3.302 1.016)
            (xy 3.302 -1.016)
            (xy 1.778 0)
            (xy 3.302 1.016)
          )
          (stroke (width 0.254) (type default))
          (fill (type outline))
        )
        (polyline
          (pts
            (xy 1.143 2.286)
            (xy 1.143 1.778)
            (xy 1.143 2.286)
            (xy 1.651 2.286)
            (xy 1.143 2.286)
            (xy 2.159 1.27)
          )
          (stroke (width 0.254) (type default))
          (fill (type none))
        )
        (polyline
          (pts
            (xy 2.159 2.54)
            (xy 2.159 2.032)
            (xy 2.159 2.54)
            (xy 2.667 2.54)
            (xy 2.159 2.54)
            (xy 3.048 1.651)
          )
          (stroke (width 0.254) (type default))
          (fill (type none))
        )
        (pin passive line (at 0 0 0) (length 0.635)
          (name "C" (effects (font (size 1.27 1.27))))
          (number "1" (effects (font (size 1.27 1.27))))
        )
        (pin passive line (at 5.08 0 180) (length 0.635)
          (name "A" (effects (font (size 1.27 1.27))))
          (number "2" (effects (font (size 1.27 1.27))))
        )
      )
    )
	(symbol "LED_G_0603_LG_L29K-G2J1-24-Z_8" (pin_numbers hide) (pin_names hide) (in_bom yes) (on_board yes)
      (property "Reference" "D" (at 20.32 -2.54 0)
        (effects (font (size 1.27 1.27) (thickness 0.15)) (justify left bottom))
      )
      (property "Value" "LED_G_0603_LG_L29K-G2J1-24-Z" (at 20.32 -7.62 0)
        (effects (font (size 1.27 1.27) (thickness 0.15)) (justify left bottom) hide)
      )
      (property "Footprint" "antmicro-footprints:LED_0603_1608Metric_G" (at 20.32 -10.16 0)
        (effects (font (size 1.27 1.27) (thickness 0.15)) (justify left bottom) hide)
      )
      (property "Datasheet" "https://look.ams-osram.com/m/19ee86b3ae0ee95b/original/LG-L29K.pdf" (at 20.32 -12.7 0)
        (effects (font (size 1.27 1.27) (thickness 0.15)) (justify left bottom) hide)
      )
      (property "MPN" "LG L29K-G2J1-24-Z" (at 20.32 -15.24 0)
        (effects (font (size 1.27 1.27) (thickness 0.15)) (justify left bottom) hide)
      )
      (property "Manufacturer" "OSRAM" (at 20.32 -17.78 0)
        (effects (font (size 1.27 1.27) (thickness 0.15)) (justify left bottom) hide)
      )
      (property "Color" "Green" (at 20.32 -5.08 0)
        (effects (font (size 1.27 1.27)) (justify left bottom))
      )
      (property "Author" "Antmicro" (at 20.32 -20.32 0)
        (effects (font (size 1.27 1.27) (thickness 0.15)) (justify left bottom) hide)
      )
      (property "License" "Apache-2.0" (at 20.32 -22.86 0)
        (effects (font (size 1.27 1.27) (thickness 0.15)) (justify left bottom) hide)
      )
      (property "ki_keywords" "SMT, DIODE, SEMICONDUCTOR, LED" (at 0 0 0)
        (effects (font (size 1.27 1.27)) hide)
      )
      (property "ki_description" "LED, Green, SMD, 0603, 20 mA, 1.7 V, 570 nm" (at 0 0 0)
        (effects (font (size 1.27 1.27)) hide)
      )
      (symbol "LED_G_0603_LG_L29K-G2J1-24-Z_8_0_1"
        (polyline
          (pts
            (xy 1.905 0)
            (xy 0.635 0)
          )
          (stroke (width 0) (type default))
          (fill (type none))
        )
        (polyline
          (pts
            (xy 4.445 0)
            (xy 3.175 0)
          )
          (stroke (width 0) (type default))
          (fill (type none))
        )
      )
      (symbol "LED_G_0603_LG_L29K-G2J1-24-Z_8_1_1"
        (polyline
          (pts
            (xy 1.778 1.016)
            (xy 1.778 -1.016)
          )
          (stroke (width 0.254) (type default))
          (fill (type none))
        )
        (polyline
          (pts
            (xy 3.302 1.016)
            (xy 3.302 -1.016)
            (xy 1.778 0)
            (xy 3.302 1.016)
          )
          (stroke (width 0.254) (type default))
          (fill (type outline))
        )
        (polyline
          (pts
            (xy 1.143 2.286)
            (xy 1.143 1.778)
            (xy 1.143 2.286)
            (xy 1.651 2.286)
            (xy 1.143 2.286)
            (xy 2.159 1.27)
          )
          (stroke (width 0.254) (type default))
          (fill (type none))
        )
        (polyline
          (pts
            (xy 2.159 2.54)
            (xy 2.159 2.032)
            (xy 2.159 2.54)
            (xy 2.667 2.54)
            (xy 2.159 2.54)
            (xy 3.048 1.651)
          )
          (stroke (width 0.254) (type default))
          (fill (type none))
        )
        (pin passive line (at 0 0 0) (length 0.635)
          (name "C" (effects (font (size 1.27 1.27))))
          (number "1" (effects (font (size 1.27 1.27))))
        )
        (pin passive line (at 5.08 0 180) (length 0.635)
          (name "A" (effects (font (size 1.27 1.27))))
          (number "2" (effects (font (size 1.27 1.27))))
        )
      )
    )
	(symbol "L_3u3_4.1A_WE-LHMI-5030_1" (pin_numbers hide) (pin_names hide) (in_bom yes) (on_board yes)
      (property "Reference" "L" (at 13.97 0 0)
        (effects (font (size 1.27 1.27) (thickness 0.15)) (justify left bottom))
      )
      (property "Value" "L_3u3_4.1A_WE-LHMI-5030" (at 13.97 -2.54 0)
        (effects (font (size 1.27 1.27) (thickness 0.15)) (justify left bottom) hide)
      )
      (property "Footprint" "antmicro-footprints:L_WE-LHMI-5030" (at 13.97 -7.62 0)
        (effects (font (size 1.27 1.27) (thickness 0.15)) (justify left bottom) hide)
      )
      (property "Datasheet" "https://www.we-online.com/catalog/datasheet/74437336033.pdf" (at 13.97 -10.16 0)
        (effects (font (size 1.27 1.27) (thickness 0.15)) (justify left bottom) hide)
      )
      (property "Val" "3u3/4.1A" (at 13.97 -5.08 0)
        (effects (font (size 1.27 1.27) (thickness 0.15)) (justify left bottom))
      )
      (property "Manufacturer" "Würth Elektronik" (at 13.97 -12.7 0)
        (effects (font (size 1.27 1.27) (thickness 0.15)) (justify left bottom) hide)
      )
      (property "MPN" "74437336033" (at 13.97 -15.24 0)
        (effects (font (size 1.27 1.27) (thickness 0.15)) (justify left bottom) hide)
      )
      (property "ISat" "5.45A" (at 13.97 -16.51 0)
        (effects (font (size 1.27 1.27)) (justify left) hide)
      )
      (property "IMax" "4.1A" (at 13.97 -20.32 0)
        (effects (font (size 1.27 1.27) (thickness 0.15)) (justify left bottom) hide)
      )
      (property "Size" "5.2x5.2" (at 13.97 -22.86 0)
        (effects (font (size 1.27 1.27) (thickness 0.15)) (justify left bottom) hide)
      )
      (property "Author" "Antmicro" (at 13.97 -25.4 0)
        (effects (font (size 1.27 1.27) (thickness 0.15)) (justify left bottom) hide)
      )
      (property "License" "Apache-2.0" (at 13.97 -27.94 0)
        (effects (font (size 1.27 1.27) (thickness 0.15)) (justify left bottom) hide)
      )
      (property "ki_keywords" "SMT, INDUCTOR, PASSIVE" (at 0 0 0)
        (effects (font (size 1.27 1.27)) hide)
      )
      (property "ki_description" "Power Inductor (SMT), 3.3 µH, 4.1 A, Shielded, 8.4 A, WE-LHMI" (at 0 0 0)
        (effects (font (size 1.27 1.27)) hide)
      )
      (symbol "L_3u3_4.1A_WE-LHMI-5030_1_0_1"
        (arc (start 1.524 0) (mid 1.016 0.5058) (end 0.508 0)
          (stroke (width 0) (type default))
          (fill (type none))
        )
        (arc (start 2.54 0) (mid 2.032 0.5058) (end 1.524 0)
          (stroke (width 0) (type default))
          (fill (type none))
        )
        (arc (start 3.556 0) (mid 3.048 0.5058) (end 2.54 0)
          (stroke (width 0) (type default))
          (fill (type none))
        )
        (arc (start 4.572 0) (mid 4.064 0.5058) (end 3.556 0)
          (stroke (width 0) (type default))
          (fill (type none))
        )
      )
      (symbol "L_3u3_4.1A_WE-LHMI-5030_1_1_1"
        (pin passive line (at 0 0 0) (length 0.508)
          (name "~" (effects (font (size 1.27 1.27))))
          (number "1" (effects (font (size 1.27 1.27))))
        )
        (pin passive line (at 5.08 0 180) (length 0.508)
          (name "~" (effects (font (size 1.27 1.27))))
          (number "2" (effects (font (size 1.27 1.27))))
        )
      )
    )
	(symbol "PESD5V0S2BQA_1" (in_bom yes) (on_board yes)
      (property "Reference" "D" (at 27.94 -2.54 0)
        (effects (font (size 1.27 1.27) (thickness 0.15)) (justify left bottom))
      )
      (property "Value" "PESD5V0S2BQA" (at 27.94 -10.16 0)
        (effects (font (size 1.27 1.27) (thickness 0.15)) (justify left bottom) hide)
      )
      (property "Footprint" "antmicro-footprints:TPD2E009DRTR" (at 27.94 -12.7 0)
        (effects (font (size 1.27 1.27) (thickness 0.15)) (justify left bottom) hide)
      )
      (property "Datasheet" "https://4donline.ihs.com/images/VipMasterIC/IC/NEXP/NEXP-S-A0003105620/NEXP-S-A0003107857-1.pdf?hkey=6D3A4C79FDBF58556ACFDE234799DDF0" (at 27.94 -15.24 0)
        (effects (font (size 1.27 1.27) (thickness 0.15)) (justify left bottom) hide)
      )
      (property "MPN" "PESD5V0S2BQA" (at 27.94 -5.08 0)
        (effects (font (size 1.27 1.27) (thickness 0.15)) (justify left bottom))
      )
      (property "Manufacturer" "Nexperia" (at 27.94 -7.62 0)
        (effects (font (size 1.27 1.27) (thickness 0.15)) (justify left bottom) hide)
      )
      (property "Author" "Antmicro" (at 27.94 -17.78 0)
        (effects (font (size 1.27 1.27) (thickness 0.15)) (justify left bottom) hide)
      )
      (property "License" "Apache-2.0" (at 27.94 -20.32 0)
        (effects (font (size 1.27 1.27) (thickness 0.15)) (justify left bottom) hide)
      )
      (property "ki_keywords" "SMT, DIODE, SEMICONDUCTOR, TVS, ESD" (at 0 0 0)
        (effects (font (size 1.27 1.27)) hide)
      )
      (property "ki_description" "TVS diode array, 30 kV, SOT-1215, 5V, 45 pF" (at 0 0 0)
        (effects (font (size 1.27 1.27)) hide)
      )
      (symbol "PESD5V0S2BQA_1_1_1"
        (polyline
          (pts
            (xy 10.414 -0.254)
            (xy 10.414 -5.842)
          )
          (stroke (width 0.254) (type default))
          (fill (type none))
        )
        (polyline
          (pts
            (xy 9.652 -2.54)
            (xy 11.176 -2.54)
            (xy 11.176 -2.794)
          )
          (stroke (width 0.254) (type default))
          (fill (type none))
        )
        (polyline
          (pts
            (xy 11.43 -4.064)
            (xy 10.414 -2.54)
            (xy 9.398 -4.064)
            (xy 11.43 -4.064)
          )
          (stroke (width 0.254) (type default))
          (fill (type none))
        )
        (rectangle (start 12.7 -7.62) (end 2.54 2.54)
          (stroke (width 0.254) (type default))
          (fill (type background))
        )
        (pin passive line (at 0 0 0) (length 2.54)
          (name "IO1" (effects (font (size 1.27 1.27))))
          (number "1" (effects (font (size 1.27 1.27))))
        )
        (pin passive line (at 0 -2.54 0) (length 2.54)
          (name "IO2" (effects (font (size 1.27 1.27))))
          (number "2" (effects (font (size 1.27 1.27))))
        )
        (pin passive line (at 0 -5.08 0) (length 2.54)
          (name "GND" (effects (font (size 1.27 1.27))))
          (number "3" (effects (font (size 1.27 1.27))))
        )
      )
    )
	(symbol "R_0R_0402_1" (pin_numbers hide) (pin_names hide) (in_bom yes) (on_board yes)
      (property "Reference" "R" (at 20.32 -5.08 0)
        (effects (font (size 1.27 1.27) (thickness 0.15)) (justify left bottom))
      )
      (property "Value" "R_0R_0402" (at 20.32 -12.7 0)
        (effects (font (size 1.27 1.27) (thickness 0.15)) (justify left bottom) hide)
      )
      (property "Footprint" "antmicro-footprints:R_0402_1005Metric" (at 20.32 -15.24 0)
        (effects (font (size 1.27 1.27) (thickness 0.15)) (justify left bottom) hide)
      )
      (property "Datasheet" "https://industrial.panasonic.com/cdbs/www-data/pdf/RDA0000/AOA0000C301.pdf" (at 20.32 -17.78 0)
        (effects (font (size 1.27 1.27) (thickness 0.15)) (justify left bottom) hide)
      )
      (property "MPN" "ERJ2GE0R00X" (at 20.32 -20.32 0)
        (effects (font (size 1.27 1.27) (thickness 0.15)) (justify left bottom) hide)
      )
      (property "Manufacturer" "Panasonic" (at 20.32 -22.86 0)
        (effects (font (size 1.27 1.27) (thickness 0.15)) (justify left bottom) hide)
      )
      (property "License" "Apache-2.0" (at 20.32 -25.4 0)
        (effects (font (size 1.27 1.27) (thickness 0.15)) (justify left bottom) hide)
      )
      (property "Author" "Antmicro" (at 20.32 -27.94 0)
        (effects (font (size 1.27 1.27) (thickness 0.15)) (justify left bottom) hide)
      )
      (property "Val" "0R" (at 20.32 -7.62 0)
        (effects (font (size 1.27 1.27) (thickness 0.15)) (justify left bottom))
      )
      (property "Tolerance" "~" (at 20.32 -10.16 0)
        (effects (font (size 1.27 1.27)) (justify left bottom) hide)
      )
      (property "Current" "1A" (at 20.32 -30.48 0)
        (effects (font (size 1.27 1.27) (thickness 0.15)) (justify left bottom) hide)
      )
      (property "ki_keywords" "0402, SMT, RESISTOR, PASSIVE" (at 0 0 0)
        (effects (font (size 1.27 1.27)) hide)
      )
      (property "ki_description" "SMD Chip Resistor, Jumper, 0 ohm, 100 mW, 0402 [1005 Metric], Thick Film, General Purpose" (at 0 0 0)
        (effects (font (size 1.27 1.27)) hide)
      )
      (symbol "R_0R_0402_1_0_1"
        (rectangle (start 0.635 0.889) (end 4.445 -0.889)
          (stroke (width 0.254) (type default))
          (fill (type none))
        )
      )
      (symbol "R_0R_0402_1_1_1"
        (pin passive line (at 0 0 0) (length 0.635)
          (name "~" (effects (font (size 1.27 1.27))))
          (number "1" (effects (font (size 1.27 1.27))))
        )
        (pin passive line (at 5.08 0 180) (length 0.635)
          (name "~" (effects (font (size 1.27 1.27))))
          (number "2" (effects (font (size 1.27 1.27))))
        )
      )
    )
	(symbol "R_0R_0402_2" (pin_numbers hide) (pin_names hide) (in_bom yes) (on_board yes)
      (property "Reference" "R" (at 20.32 -5.08 0)
        (effects (font (size 1.27 1.27) (thickness 0.15)) (justify left bottom))
      )
      (property "Value" "R_0R_0402" (at 20.32 -12.7 0)
        (effects (font (size 1.27 1.27) (thickness 0.15)) (justify left bottom) hide)
      )
      (property "Footprint" "antmicro-footprints:R_0402_1005Metric" (at 20.32 -15.24 0)
        (effects (font (size 1.27 1.27) (thickness 0.15)) (justify left bottom) hide)
      )
      (property "Datasheet" "https://industrial.panasonic.com/cdbs/www-data/pdf/RDA0000/AOA0000C301.pdf" (at 20.32 -17.78 0)
        (effects (font (size 1.27 1.27) (thickness 0.15)) (justify left bottom) hide)
      )
      (property "MPN" "ERJ2GE0R00X" (at 20.32 -20.32 0)
        (effects (font (size 1.27 1.27) (thickness 0.15)) (justify left bottom) hide)
      )
      (property "Manufacturer" "Panasonic" (at 20.32 -22.86 0)
        (effects (font (size 1.27 1.27) (thickness 0.15)) (justify left bottom) hide)
      )
      (property "License" "Apache-2.0" (at 20.32 -25.4 0)
        (effects (font (size 1.27 1.27) (thickness 0.15)) (justify left bottom) hide)
      )
      (property "Author" "Antmicro" (at 20.32 -27.94 0)
        (effects (font (size 1.27 1.27) (thickness 0.15)) (justify left bottom) hide)
      )
      (property "Val" "0R" (at 20.32 -7.62 0)
        (effects (font (size 1.27 1.27) (thickness 0.15)) (justify left bottom))
      )
      (property "Tolerance" "~" (at 20.32 -10.16 0)
        (effects (font (size 1.27 1.27)) (justify left bottom) hide)
      )
      (property "Current" "1A" (at 20.32 -30.48 0)
        (effects (font (size 1.27 1.27) (thickness 0.15)) (justify left bottom) hide)
      )
      (property "ki_keywords" "0402, SMT, RESISTOR, PASSIVE" (at 0 0 0)
        (effects (font (size 1.27 1.27)) hide)
      )
      (property "ki_description" "SMD Chip Resistor, Jumper, 0 ohm, 100 mW, 0402 [1005 Metric], Thick Film, General Purpose" (at 0 0 0)
        (effects (font (size 1.27 1.27)) hide)
      )
      (symbol "R_0R_0402_2_0_1"
        (rectangle (start 0.635 0.889) (end 4.445 -0.889)
          (stroke (width 0.254) (type default))
          (fill (type none))
        )
      )
      (symbol "R_0R_0402_2_1_1"
        (pin passive line (at 0 0 0) (length 0.635)
          (name "~" (effects (font (size 1.27 1.27))))
          (number "1" (effects (font (size 1.27 1.27))))
        )
        (pin passive line (at 5.08 0 180) (length 0.635)
          (name "~" (effects (font (size 1.27 1.27))))
          (number "2" (effects (font (size 1.27 1.27))))
        )
      )
    )
	(symbol "R_0R_0402_3" (pin_numbers hide) (pin_names hide) (in_bom yes) (on_board yes)
      (property "Reference" "R" (at 20.32 -5.08 0)
        (effects (font (size 1.27 1.27) (thickness 0.15)) (justify left bottom))
      )
      (property "Value" "R_0R_0402" (at 20.32 -12.7 0)
        (effects (font (size 1.27 1.27) (thickness 0.15)) (justify left bottom) hide)
      )
      (property "Footprint" "antmicro-footprints:R_0402_1005Metric" (at 20.32 -15.24 0)
        (effects (font (size 1.27 1.27) (thickness 0.15)) (justify left bottom) hide)
      )
      (property "Datasheet" "https://industrial.panasonic.com/cdbs/www-data/pdf/RDA0000/AOA0000C301.pdf" (at 20.32 -17.78 0)
        (effects (font (size 1.27 1.27) (thickness 0.15)) (justify left bottom) hide)
      )
      (property "MPN" "ERJ2GE0R00X" (at 20.32 -20.32 0)
        (effects (font (size 1.27 1.27) (thickness 0.15)) (justify left bottom) hide)
      )
      (property "Manufacturer" "Panasonic" (at 20.32 -22.86 0)
        (effects (font (size 1.27 1.27) (thickness 0.15)) (justify left bottom) hide)
      )
      (property "License" "Apache-2.0" (at 20.32 -25.4 0)
        (effects (font (size 1.27 1.27) (thickness 0.15)) (justify left bottom) hide)
      )
      (property "Author" "Antmicro" (at 20.32 -27.94 0)
        (effects (font (size 1.27 1.27) (thickness 0.15)) (justify left bottom) hide)
      )
      (property "Val" "0R" (at 20.32 -7.62 0)
        (effects (font (size 1.27 1.27) (thickness 0.15)) (justify left bottom))
      )
      (property "Tolerance" "~" (at 20.32 -10.16 0)
        (effects (font (size 1.27 1.27)) (justify left bottom) hide)
      )
      (property "Current" "1A" (at 20.32 -30.48 0)
        (effects (font (size 1.27 1.27) (thickness 0.15)) (justify left bottom) hide)
      )
      (property "ki_keywords" "0402, SMT, RESISTOR, PASSIVE" (at 0 0 0)
        (effects (font (size 1.27 1.27)) hide)
      )
      (property "ki_description" "SMD Chip Resistor, Jumper, 0 ohm, 100 mW, 0402 [1005 Metric], Thick Film, General Purpose" (at 0 0 0)
        (effects (font (size 1.27 1.27)) hide)
      )
      (symbol "R_0R_0402_3_0_1"
        (rectangle (start 0.635 0.889) (end 4.445 -0.889)
          (stroke (width 0.254) (type default))
          (fill (type none))
        )
      )
      (symbol "R_0R_0402_3_1_1"
        (pin passive line (at 0 0 0) (length 0.635)
          (name "~" (effects (font (size 1.27 1.27))))
          (number "1" (effects (font (size 1.27 1.27))))
        )
        (pin passive line (at 5.08 0 180) (length 0.635)
          (name "~" (effects (font (size 1.27 1.27))))
          (number "2" (effects (font (size 1.27 1.27))))
        )
      )
    )
	(symbol "R_0R_0402_4" (pin_numbers hide) (pin_names hide) (in_bom yes) (on_board yes)
      (property "Reference" "R" (at 20.32 -5.08 0)
        (effects (font (size 1.27 1.27) (thickness 0.15)) (justify left bottom))
      )
      (property "Value" "R_0R_0402" (at 20.32 -12.7 0)
        (effects (font (size 1.27 1.27) (thickness 0.15)) (justify left bottom) hide)
      )
      (property "Footprint" "antmicro-footprints:R_0402_1005Metric" (at 20.32 -15.24 0)
        (effects (font (size 1.27 1.27) (thickness 0.15)) (justify left bottom) hide)
      )
      (property "Datasheet" "https://industrial.panasonic.com/cdbs/www-data/pdf/RDA0000/AOA0000C301.pdf" (at 20.32 -17.78 0)
        (effects (font (size 1.27 1.27) (thickness 0.15)) (justify left bottom) hide)
      )
      (property "MPN" "ERJ2GE0R00X" (at 20.32 -20.32 0)
        (effects (font (size 1.27 1.27) (thickness 0.15)) (justify left bottom) hide)
      )
      (property "Manufacturer" "Panasonic" (at 20.32 -22.86 0)
        (effects (font (size 1.27 1.27) (thickness 0.15)) (justify left bottom) hide)
      )
      (property "License" "Apache-2.0" (at 20.32 -25.4 0)
        (effects (font (size 1.27 1.27) (thickness 0.15)) (justify left bottom) hide)
      )
      (property "Author" "Antmicro" (at 20.32 -27.94 0)
        (effects (font (size 1.27 1.27) (thickness 0.15)) (justify left bottom) hide)
      )
      (property "Val" "0R" (at 20.32 -7.62 0)
        (effects (font (size 1.27 1.27) (thickness 0.15)) (justify left bottom))
      )
      (property "Tolerance" "~" (at 20.32 -10.16 0)
        (effects (font (size 1.27 1.27)) (justify left bottom) hide)
      )
      (property "Current" "1A" (at 20.32 -30.48 0)
        (effects (font (size 1.27 1.27) (thickness 0.15)) (justify left bottom) hide)
      )
      (property "ki_keywords" "0402, SMT, RESISTOR, PASSIVE" (at 0 0 0)
        (effects (font (size 1.27 1.27)) hide)
      )
      (property "ki_description" "SMD Chip Resistor, Jumper, 0 ohm, 100 mW, 0402 [1005 Metric], Thick Film, General Purpose" (at 0 0 0)
        (effects (font (size 1.27 1.27)) hide)
      )
      (symbol "R_0R_0402_4_0_1"
        (rectangle (start 0.635 0.889) (end 4.445 -0.889)
          (stroke (width 0.254) (type default))
          (fill (type none))
        )
      )
      (symbol "R_0R_0402_4_1_1"
        (pin passive line (at 0 0 0) (length 0.635)
          (name "~" (effects (font (size 1.27 1.27))))
          (number "1" (effects (font (size 1.27 1.27))))
        )
        (pin passive line (at 5.08 0 180) (length 0.635)
          (name "~" (effects (font (size 1.27 1.27))))
          (number "2" (effects (font (size 1.27 1.27))))
        )
      )
    )
	(symbol "R_0R_0402_5" (pin_numbers hide) (pin_names hide) (in_bom yes) (on_board yes)
      (property "Reference" "R" (at 20.32 -5.08 0)
        (effects (font (size 1.27 1.27) (thickness 0.15)) (justify left bottom))
      )
      (property "Value" "R_0R_0402" (at 20.32 -12.7 0)
        (effects (font (size 1.27 1.27) (thickness 0.15)) (justify left bottom) hide)
      )
      (property "Footprint" "antmicro-footprints:R_0402_1005Metric" (at 20.32 -15.24 0)
        (effects (font (size 1.27 1.27) (thickness 0.15)) (justify left bottom) hide)
      )
      (property "Datasheet" "https://industrial.panasonic.com/cdbs/www-data/pdf/RDA0000/AOA0000C301.pdf" (at 20.32 -17.78 0)
        (effects (font (size 1.27 1.27) (thickness 0.15)) (justify left bottom) hide)
      )
      (property "MPN" "ERJ2GE0R00X" (at 20.32 -20.32 0)
        (effects (font (size 1.27 1.27) (thickness 0.15)) (justify left bottom) hide)
      )
      (property "Manufacturer" "Panasonic" (at 20.32 -22.86 0)
        (effects (font (size 1.27 1.27) (thickness 0.15)) (justify left bottom) hide)
      )
      (property "License" "Apache-2.0" (at 20.32 -25.4 0)
        (effects (font (size 1.27 1.27) (thickness 0.15)) (justify left bottom) hide)
      )
      (property "Author" "Antmicro" (at 20.32 -27.94 0)
        (effects (font (size 1.27 1.27) (thickness 0.15)) (justify left bottom) hide)
      )
      (property "Val" "0R" (at 20.32 -7.62 0)
        (effects (font (size 1.27 1.27) (thickness 0.15)) (justify left bottom))
      )
      (property "Tolerance" "~" (at 20.32 -10.16 0)
        (effects (font (size 1.27 1.27)) (justify left bottom) hide)
      )
      (property "Current" "1A" (at 20.32 -30.48 0)
        (effects (font (size 1.27 1.27) (thickness 0.15)) (justify left bottom) hide)
      )
      (property "ki_keywords" "0402, SMT, RESISTOR, PASSIVE" (at 0 0 0)
        (effects (font (size 1.27 1.27)) hide)
      )
      (property "ki_description" "SMD Chip Resistor, Jumper, 0 ohm, 100 mW, 0402 [1005 Metric], Thick Film, General Purpose" (at 0 0 0)
        (effects (font (size 1.27 1.27)) hide)
      )
      (symbol "R_0R_0402_5_0_1"
        (rectangle (start 0.635 0.889) (end 4.445 -0.889)
          (stroke (width 0.254) (type default))
          (fill (type none))
        )
      )
      (symbol "R_0R_0402_5_1_1"
        (pin passive line (at 0 0 0) (length 0.635)
          (name "~" (effects (font (size 1.27 1.27))))
          (number "1" (effects (font (size 1.27 1.27))))
        )
        (pin passive line (at 5.08 0 180) (length 0.635)
          (name "~" (effects (font (size 1.27 1.27))))
          (number "2" (effects (font (size 1.27 1.27))))
        )
      )
    )
	(symbol "R_0R_0402_6" (pin_numbers hide) (pin_names hide) (in_bom yes) (on_board yes)
      (property "Reference" "R" (at 20.32 -5.08 0)
        (effects (font (size 1.27 1.27) (thickness 0.15)) (justify left bottom))
      )
      (property "Value" "R_0R_0402" (at 20.32 -12.7 0)
        (effects (font (size 1.27 1.27) (thickness 0.15)) (justify left bottom) hide)
      )
      (property "Footprint" "antmicro-footprints:R_0402_1005Metric" (at 20.32 -15.24 0)
        (effects (font (size 1.27 1.27) (thickness 0.15)) (justify left bottom) hide)
      )
      (property "Datasheet" "https://industrial.panasonic.com/cdbs/www-data/pdf/RDA0000/AOA0000C301.pdf" (at 20.32 -17.78 0)
        (effects (font (size 1.27 1.27) (thickness 0.15)) (justify left bottom) hide)
      )
      (property "MPN" "ERJ2GE0R00X" (at 20.32 -20.32 0)
        (effects (font (size 1.27 1.27) (thickness 0.15)) (justify left bottom) hide)
      )
      (property "Manufacturer" "Panasonic" (at 20.32 -22.86 0)
        (effects (font (size 1.27 1.27) (thickness 0.15)) (justify left bottom) hide)
      )
      (property "License" "Apache-2.0" (at 20.32 -25.4 0)
        (effects (font (size 1.27 1.27) (thickness 0.15)) (justify left bottom) hide)
      )
      (property "Author" "Antmicro" (at 20.32 -27.94 0)
        (effects (font (size 1.27 1.27) (thickness 0.15)) (justify left bottom) hide)
      )
      (property "Val" "0R" (at 20.32 -7.62 0)
        (effects (font (size 1.27 1.27) (thickness 0.15)) (justify left bottom))
      )
      (property "Tolerance" "~" (at 20.32 -10.16 0)
        (effects (font (size 1.27 1.27)) (justify left bottom) hide)
      )
      (property "Current" "1A" (at 20.32 -30.48 0)
        (effects (font (size 1.27 1.27) (thickness 0.15)) (justify left bottom) hide)
      )
      (property "ki_keywords" "0402, SMT, RESISTOR, PASSIVE" (at 0 0 0)
        (effects (font (size 1.27 1.27)) hide)
      )
      (property "ki_description" "SMD Chip Resistor, Jumper, 0 ohm, 100 mW, 0402 [1005 Metric], Thick Film, General Purpose" (at 0 0 0)
        (effects (font (size 1.27 1.27)) hide)
      )
      (symbol "R_0R_0402_6_0_1"
        (rectangle (start 0.635 0.889) (end 4.445 -0.889)
          (stroke (width 0.254) (type default))
          (fill (type none))
        )
      )
      (symbol "R_0R_0402_6_1_1"
        (pin passive line (at 0 0 0) (length 0.635)
          (name "~" (effects (font (size 1.27 1.27))))
          (number "1" (effects (font (size 1.27 1.27))))
        )
        (pin passive line (at 5.08 0 180) (length 0.635)
          (name "~" (effects (font (size 1.27 1.27))))
          (number "2" (effects (font (size 1.27 1.27))))
        )
      )
    )
	(symbol "R_0R_0402_7" (pin_numbers hide) (pin_names hide) (in_bom yes) (on_board yes)
      (property "Reference" "R" (at 20.32 -5.08 0)
        (effects (font (size 1.27 1.27) (thickness 0.15)) (justify left bottom))
      )
      (property "Value" "R_0R_0402" (at 20.32 -12.7 0)
        (effects (font (size 1.27 1.27) (thickness 0.15)) (justify left bottom) hide)
      )
      (property "Footprint" "antmicro-footprints:R_0402_1005Metric" (at 20.32 -15.24 0)
        (effects (font (size 1.27 1.27) (thickness 0.15)) (justify left bottom) hide)
      )
      (property "Datasheet" "https://industrial.panasonic.com/cdbs/www-data/pdf/RDA0000/AOA0000C301.pdf" (at 20.32 -17.78 0)
        (effects (font (size 1.27 1.27) (thickness 0.15)) (justify left bottom) hide)
      )
      (property "MPN" "ERJ2GE0R00X" (at 20.32 -20.32 0)
        (effects (font (size 1.27 1.27) (thickness 0.15)) (justify left bottom) hide)
      )
      (property "Manufacturer" "Panasonic" (at 20.32 -22.86 0)
        (effects (font (size 1.27 1.27) (thickness 0.15)) (justify left bottom) hide)
      )
      (property "License" "Apache-2.0" (at 20.32 -25.4 0)
        (effects (font (size 1.27 1.27) (thickness 0.15)) (justify left bottom) hide)
      )
      (property "Author" "Antmicro" (at 20.32 -27.94 0)
        (effects (font (size 1.27 1.27) (thickness 0.15)) (justify left bottom) hide)
      )
      (property "Val" "0R" (at 20.32 -7.62 0)
        (effects (font (size 1.27 1.27) (thickness 0.15)) (justify left bottom))
      )
      (property "Tolerance" "~" (at 20.32 -10.16 0)
        (effects (font (size 1.27 1.27)) (justify left bottom) hide)
      )
      (property "Current" "1A" (at 20.32 -30.48 0)
        (effects (font (size 1.27 1.27) (thickness 0.15)) (justify left bottom) hide)
      )
      (property "ki_keywords" "0402, SMT, RESISTOR, PASSIVE" (at 0 0 0)
        (effects (font (size 1.27 1.27)) hide)
      )
      (property "ki_description" "SMD Chip Resistor, Jumper, 0 ohm, 100 mW, 0402 [1005 Metric], Thick Film, General Purpose" (at 0 0 0)
        (effects (font (size 1.27 1.27)) hide)
      )
      (symbol "R_0R_0402_7_0_1"
        (rectangle (start 0.635 0.889) (end 4.445 -0.889)
          (stroke (width 0.254) (type default))
          (fill (type none))
        )
      )
      (symbol "R_0R_0402_7_1_1"
        (pin passive line (at 0 0 0) (length 0.635)
          (name "~" (effects (font (size 1.27 1.27))))
          (number "1" (effects (font (size 1.27 1.27))))
        )
        (pin passive line (at 5.08 0 180) (length 0.635)
          (name "~" (effects (font (size 1.27 1.27))))
          (number "2" (effects (font (size 1.27 1.27))))
        )
      )
    )
	(symbol "R_0R_0402_8" (pin_numbers hide) (pin_names hide) (in_bom yes) (on_board yes)
      (property "Reference" "R" (at 20.32 -5.08 0)
        (effects (font (size 1.27 1.27) (thickness 0.15)) (justify left bottom))
      )
      (property "Value" "R_0R_0402" (at 20.32 -12.7 0)
        (effects (font (size 1.27 1.27) (thickness 0.15)) (justify left bottom) hide)
      )
      (property "Footprint" "antmicro-footprints:R_0402_1005Metric" (at 20.32 -15.24 0)
        (effects (font (size 1.27 1.27) (thickness 0.15)) (justify left bottom) hide)
      )
      (property "Datasheet" "https://industrial.panasonic.com/cdbs/www-data/pdf/RDA0000/AOA0000C301.pdf" (at 20.32 -17.78 0)
        (effects (font (size 1.27 1.27) (thickness 0.15)) (justify left bottom) hide)
      )
      (property "MPN" "ERJ2GE0R00X" (at 20.32 -20.32 0)
        (effects (font (size 1.27 1.27) (thickness 0.15)) (justify left bottom) hide)
      )
      (property "Manufacturer" "Panasonic" (at 20.32 -22.86 0)
        (effects (font (size 1.27 1.27) (thickness 0.15)) (justify left bottom) hide)
      )
      (property "License" "Apache-2.0" (at 20.32 -25.4 0)
        (effects (font (size 1.27 1.27) (thickness 0.15)) (justify left bottom) hide)
      )
      (property "Author" "Antmicro" (at 20.32 -27.94 0)
        (effects (font (size 1.27 1.27) (thickness 0.15)) (justify left bottom) hide)
      )
      (property "Val" "0R" (at 20.32 -7.62 0)
        (effects (font (size 1.27 1.27) (thickness 0.15)) (justify left bottom))
      )
      (property "Tolerance" "~" (at 20.32 -10.16 0)
        (effects (font (size 1.27 1.27)) (justify left bottom) hide)
      )
      (property "Current" "1A" (at 20.32 -30.48 0)
        (effects (font (size 1.27 1.27) (thickness 0.15)) (justify left bottom) hide)
      )
      (property "ki_keywords" "0402, SMT, RESISTOR, PASSIVE" (at 0 0 0)
        (effects (font (size 1.27 1.27)) hide)
      )
      (property "ki_description" "SMD Chip Resistor, Jumper, 0 ohm, 100 mW, 0402 [1005 Metric], Thick Film, General Purpose" (at 0 0 0)
        (effects (font (size 1.27 1.27)) hide)
      )
      (symbol "R_0R_0402_8_0_1"
        (rectangle (start 0.635 0.889) (end 4.445 -0.889)
          (stroke (width 0.254) (type default))
          (fill (type none))
        )
      )
      (symbol "R_0R_0402_8_1_1"
        (pin passive line (at 0 0 0) (length 0.635)
          (name "~" (effects (font (size 1.27 1.27))))
          (number "1" (effects (font (size 1.27 1.27))))
        )
        (pin passive line (at 5.08 0 180) (length 0.635)
          (name "~" (effects (font (size 1.27 1.27))))
          (number "2" (effects (font (size 1.27 1.27))))
        )
      )
    )
	(symbol "R_0R_0603_1" (pin_numbers hide) (pin_names hide) (in_bom yes) (on_board yes)
      (property "Reference" "R" (at 20.32 -5.08 0)
        (effects (font (size 1.27 1.27) (thickness 0.15)) (justify left bottom))
      )
      (property "Value" "R_0R_0603" (at 20.32 -12.7 0)
        (effects (font (size 1.27 1.27) (thickness 0.15)) (justify left bottom) hide)
      )
      (property "Footprint" "antmicro-footprints:R_0603_1608Metric" (at 20.32 -15.24 0)
        (effects (font (size 1.27 1.27) (thickness 0.15)) (justify left bottom) hide)
      )
      (property "Datasheet" "https://www.bourns.com/docs/product-datasheets/cr.pdf?sfvrsn=574d41f6_14" (at 20.32 -17.78 0)
        (effects (font (size 1.27 1.27) (thickness 0.15)) (justify left bottom) hide)
      )
      (property "MPN" "CR0603-J/-000ELF" (at 20.32 -20.32 0)
        (effects (font (size 1.27 1.27) (thickness 0.15)) (justify left bottom) hide)
      )
      (property "Manufacturer" "Bourns" (at 20.32 -22.86 0)
        (effects (font (size 1.27 1.27) (thickness 0.15)) (justify left bottom) hide)
      )
      (property "License" "Apache-2.0" (at 20.32 -25.4 0)
        (effects (font (size 1.27 1.27) (thickness 0.15)) (justify left bottom) hide)
      )
      (property "Author" "Antmicro" (at 20.32 -27.94 0)
        (effects (font (size 1.27 1.27) (thickness 0.15)) (justify left bottom) hide)
      )
      (property "Val" "0R" (at 20.32 -7.62 0)
        (effects (font (size 1.27 1.27) (thickness 0.15)) (justify left bottom))
      )
      (property "Tolerance" "~" (at 20.32 -10.16 0)
        (effects (font (size 1.27 1.27)) (justify left bottom) hide)
      )
      (property "Current" "1A" (at 20.32 -30.48 0)
        (effects (font (size 1.27 1.27) (thickness 0.15)) (justify left bottom) hide)
      )
      (property "ki_keywords" "0603, SMT, RESISTOR, PASSIVE" (at 0 0 0)
        (effects (font (size 1.27 1.27)) hide)
      )
      (property "ki_description" "Zero Ohm Resistor, Jumper, 0603 [1608 Metric], Thick Film, 100 mW, 1 A, Surface Mount Device, CR" (at 0 0 0)
        (effects (font (size 1.27 1.27)) hide)
      )
      (symbol "R_0R_0603_1_0_1"
        (rectangle (start 0.635 0.889) (end 4.445 -0.889)
          (stroke (width 0.254) (type default))
          (fill (type none))
        )
      )
      (symbol "R_0R_0603_1_1_1"
        (pin passive line (at 0 0 0) (length 0.635)
          (name "~" (effects (font (size 1.27 1.27))))
          (number "1" (effects (font (size 1.27 1.27))))
        )
        (pin passive line (at 5.08 0 180) (length 0.635)
          (name "~" (effects (font (size 1.27 1.27))))
          (number "2" (effects (font (size 1.27 1.27))))
        )
      )
    )
	(symbol "R_0R_0603_2" (pin_numbers hide) (pin_names hide) (in_bom yes) (on_board yes)
      (property "Reference" "R" (at 20.32 -5.08 0)
        (effects (font (size 1.27 1.27) (thickness 0.15)) (justify left bottom))
      )
      (property "Value" "R_0R_0603" (at 20.32 -12.7 0)
        (effects (font (size 1.27 1.27) (thickness 0.15)) (justify left bottom) hide)
      )
      (property "Footprint" "antmicro-footprints:R_0603_1608Metric" (at 20.32 -15.24 0)
        (effects (font (size 1.27 1.27) (thickness 0.15)) (justify left bottom) hide)
      )
      (property "Datasheet" "https://www.bourns.com/docs/product-datasheets/cr.pdf?sfvrsn=574d41f6_14" (at 20.32 -17.78 0)
        (effects (font (size 1.27 1.27) (thickness 0.15)) (justify left bottom) hide)
      )
      (property "MPN" "CR0603-J/-000ELF" (at 20.32 -20.32 0)
        (effects (font (size 1.27 1.27) (thickness 0.15)) (justify left bottom) hide)
      )
      (property "Manufacturer" "Bourns" (at 20.32 -22.86 0)
        (effects (font (size 1.27 1.27) (thickness 0.15)) (justify left bottom) hide)
      )
      (property "License" "Apache-2.0" (at 20.32 -25.4 0)
        (effects (font (size 1.27 1.27) (thickness 0.15)) (justify left bottom) hide)
      )
      (property "Author" "Antmicro" (at 20.32 -27.94 0)
        (effects (font (size 1.27 1.27) (thickness 0.15)) (justify left bottom) hide)
      )
      (property "Val" "0R" (at 20.32 -7.62 0)
        (effects (font (size 1.27 1.27) (thickness 0.15)) (justify left bottom))
      )
      (property "Tolerance" "~" (at 20.32 -10.16 0)
        (effects (font (size 1.27 1.27)) (justify left bottom) hide)
      )
      (property "Current" "1A" (at 20.32 -30.48 0)
        (effects (font (size 1.27 1.27) (thickness 0.15)) (justify left bottom) hide)
      )
      (property "ki_keywords" "0603, SMT, RESISTOR, PASSIVE" (at 0 0 0)
        (effects (font (size 1.27 1.27)) hide)
      )
      (property "ki_description" "Zero Ohm Resistor, Jumper, 0603 [1608 Metric], Thick Film, 100 mW, 1 A, Surface Mount Device, CR" (at 0 0 0)
        (effects (font (size 1.27 1.27)) hide)
      )
      (symbol "R_0R_0603_2_0_1"
        (rectangle (start 0.635 0.889) (end 4.445 -0.889)
          (stroke (width 0.254) (type default))
          (fill (type none))
        )
      )
      (symbol "R_0R_0603_2_1_1"
        (pin passive line (at 0 0 0) (length 0.635)
          (name "~" (effects (font (size 1.27 1.27))))
          (number "1" (effects (font (size 1.27 1.27))))
        )
        (pin passive line (at 5.08 0 180) (length 0.635)
          (name "~" (effects (font (size 1.27 1.27))))
          (number "2" (effects (font (size 1.27 1.27))))
        )
      )
    )
	(symbol "R_0R_0603_3" (pin_numbers hide) (pin_names hide) (in_bom yes) (on_board yes)
      (property "Reference" "R" (at 20.32 -5.08 0)
        (effects (font (size 1.27 1.27) (thickness 0.15)) (justify left bottom))
      )
      (property "Value" "R_0R_0603" (at 20.32 -12.7 0)
        (effects (font (size 1.27 1.27) (thickness 0.15)) (justify left bottom) hide)
      )
      (property "Footprint" "antmicro-footprints:R_0603_1608Metric" (at 20.32 -15.24 0)
        (effects (font (size 1.27 1.27) (thickness 0.15)) (justify left bottom) hide)
      )
      (property "Datasheet" "https://www.bourns.com/docs/product-datasheets/cr.pdf?sfvrsn=574d41f6_14" (at 20.32 -17.78 0)
        (effects (font (size 1.27 1.27) (thickness 0.15)) (justify left bottom) hide)
      )
      (property "MPN" "CR0603-J/-000ELF" (at 20.32 -20.32 0)
        (effects (font (size 1.27 1.27) (thickness 0.15)) (justify left bottom) hide)
      )
      (property "Manufacturer" "Bourns" (at 20.32 -22.86 0)
        (effects (font (size 1.27 1.27) (thickness 0.15)) (justify left bottom) hide)
      )
      (property "License" "Apache-2.0" (at 20.32 -25.4 0)
        (effects (font (size 1.27 1.27) (thickness 0.15)) (justify left bottom) hide)
      )
      (property "Author" "Antmicro" (at 20.32 -27.94 0)
        (effects (font (size 1.27 1.27) (thickness 0.15)) (justify left bottom) hide)
      )
      (property "Val" "0R" (at 20.32 -7.62 0)
        (effects (font (size 1.27 1.27) (thickness 0.15)) (justify left bottom))
      )
      (property "Tolerance" "~" (at 20.32 -10.16 0)
        (effects (font (size 1.27 1.27)) (justify left bottom) hide)
      )
      (property "Current" "1A" (at 20.32 -30.48 0)
        (effects (font (size 1.27 1.27) (thickness 0.15)) (justify left bottom) hide)
      )
      (property "ki_keywords" "0603, SMT, RESISTOR, PASSIVE" (at 0 0 0)
        (effects (font (size 1.27 1.27)) hide)
      )
      (property "ki_description" "Zero Ohm Resistor, Jumper, 0603 [1608 Metric], Thick Film, 100 mW, 1 A, Surface Mount Device, CR" (at 0 0 0)
        (effects (font (size 1.27 1.27)) hide)
      )
      (symbol "R_0R_0603_3_0_1"
        (rectangle (start 0.635 0.889) (end 4.445 -0.889)
          (stroke (width 0.254) (type default))
          (fill (type none))
        )
      )
      (symbol "R_0R_0603_3_1_1"
        (pin passive line (at 0 0 0) (length 0.635)
          (name "~" (effects (font (size 1.27 1.27))))
          (number "1" (effects (font (size 1.27 1.27))))
        )
        (pin passive line (at 5.08 0 180) (length 0.635)
          (name "~" (effects (font (size 1.27 1.27))))
          (number "2" (effects (font (size 1.27 1.27))))
        )
      )
    )
	(symbol "R_0R_0603_4" (pin_numbers hide) (pin_names hide) (in_bom yes) (on_board yes)
      (property "Reference" "R" (at 20.32 -5.08 0)
        (effects (font (size 1.27 1.27) (thickness 0.15)) (justify left bottom))
      )
      (property "Value" "R_0R_0603" (at 20.32 -12.7 0)
        (effects (font (size 1.27 1.27) (thickness 0.15)) (justify left bottom) hide)
      )
      (property "Footprint" "antmicro-footprints:R_0603_1608Metric" (at 20.32 -15.24 0)
        (effects (font (size 1.27 1.27) (thickness 0.15)) (justify left bottom) hide)
      )
      (property "Datasheet" "https://www.bourns.com/docs/product-datasheets/cr.pdf?sfvrsn=574d41f6_14" (at 20.32 -17.78 0)
        (effects (font (size 1.27 1.27) (thickness 0.15)) (justify left bottom) hide)
      )
      (property "MPN" "CR0603-J/-000ELF" (at 20.32 -20.32 0)
        (effects (font (size 1.27 1.27) (thickness 0.15)) (justify left bottom) hide)
      )
      (property "Manufacturer" "Bourns" (at 20.32 -22.86 0)
        (effects (font (size 1.27 1.27) (thickness 0.15)) (justify left bottom) hide)
      )
      (property "License" "Apache-2.0" (at 20.32 -25.4 0)
        (effects (font (size 1.27 1.27) (thickness 0.15)) (justify left bottom) hide)
      )
      (property "Author" "Antmicro" (at 20.32 -27.94 0)
        (effects (font (size 1.27 1.27) (thickness 0.15)) (justify left bottom) hide)
      )
      (property "Val" "0R" (at 20.32 -7.62 0)
        (effects (font (size 1.27 1.27) (thickness 0.15)) (justify left bottom))
      )
      (property "Tolerance" "~" (at 20.32 -10.16 0)
        (effects (font (size 1.27 1.27)) (justify left bottom) hide)
      )
      (property "Current" "1A" (at 20.32 -30.48 0)
        (effects (font (size 1.27 1.27) (thickness 0.15)) (justify left bottom) hide)
      )
      (property "ki_keywords" "0603, SMT, RESISTOR, PASSIVE" (at 0 0 0)
        (effects (font (size 1.27 1.27)) hide)
      )
      (property "ki_description" "Zero Ohm Resistor, Jumper, 0603 [1608 Metric], Thick Film, 100 mW, 1 A, Surface Mount Device, CR" (at 0 0 0)
        (effects (font (size 1.27 1.27)) hide)
      )
      (symbol "R_0R_0603_4_0_1"
        (rectangle (start 0.635 0.889) (end 4.445 -0.889)
          (stroke (width 0.254) (type default))
          (fill (type none))
        )
      )
      (symbol "R_0R_0603_4_1_1"
        (pin passive line (at 0 0 0) (length 0.635)
          (name "~" (effects (font (size 1.27 1.27))))
          (number "1" (effects (font (size 1.27 1.27))))
        )
        (pin passive line (at 5.08 0 180) (length 0.635)
          (name "~" (effects (font (size 1.27 1.27))))
          (number "2" (effects (font (size 1.27 1.27))))
        )
      )
    )
	(symbol "R_0R_0603_5" (pin_numbers hide) (pin_names hide) (in_bom yes) (on_board yes)
      (property "Reference" "R" (at 20.32 -5.08 0)
        (effects (font (size 1.27 1.27) (thickness 0.15)) (justify left bottom))
      )
      (property "Value" "R_0R_0603" (at 20.32 -12.7 0)
        (effects (font (size 1.27 1.27) (thickness 0.15)) (justify left bottom) hide)
      )
      (property "Footprint" "antmicro-footprints:R_0603_1608Metric" (at 20.32 -15.24 0)
        (effects (font (size 1.27 1.27) (thickness 0.15)) (justify left bottom) hide)
      )
      (property "Datasheet" "https://www.bourns.com/docs/product-datasheets/cr.pdf?sfvrsn=574d41f6_14" (at 20.32 -17.78 0)
        (effects (font (size 1.27 1.27) (thickness 0.15)) (justify left bottom) hide)
      )
      (property "MPN" "CR0603-J/-000ELF" (at 20.32 -20.32 0)
        (effects (font (size 1.27 1.27) (thickness 0.15)) (justify left bottom) hide)
      )
      (property "Manufacturer" "Bourns" (at 20.32 -22.86 0)
        (effects (font (size 1.27 1.27) (thickness 0.15)) (justify left bottom) hide)
      )
      (property "License" "Apache-2.0" (at 20.32 -25.4 0)
        (effects (font (size 1.27 1.27) (thickness 0.15)) (justify left bottom) hide)
      )
      (property "Author" "Antmicro" (at 20.32 -27.94 0)
        (effects (font (size 1.27 1.27) (thickness 0.15)) (justify left bottom) hide)
      )
      (property "Val" "0R" (at 20.32 -7.62 0)
        (effects (font (size 1.27 1.27) (thickness 0.15)) (justify left bottom))
      )
      (property "Tolerance" "~" (at 20.32 -10.16 0)
        (effects (font (size 1.27 1.27)) (justify left bottom) hide)
      )
      (property "Current" "1A" (at 20.32 -30.48 0)
        (effects (font (size 1.27 1.27) (thickness 0.15)) (justify left bottom) hide)
      )
      (property "ki_keywords" "0603, SMT, RESISTOR, PASSIVE" (at 0 0 0)
        (effects (font (size 1.27 1.27)) hide)
      )
      (property "ki_description" "Zero Ohm Resistor, Jumper, 0603 [1608 Metric], Thick Film, 100 mW, 1 A, Surface Mount Device, CR" (at 0 0 0)
        (effects (font (size 1.27 1.27)) hide)
      )
      (symbol "R_0R_0603_5_0_1"
        (rectangle (start 0.635 0.889) (end 4.445 -0.889)
          (stroke (width 0.254) (type default))
          (fill (type none))
        )
      )
      (symbol "R_0R_0603_5_1_1"
        (pin passive line (at 0 0 0) (length 0.635)
          (name "~" (effects (font (size 1.27 1.27))))
          (number "1" (effects (font (size 1.27 1.27))))
        )
        (pin passive line (at 5.08 0 180) (length 0.635)
          (name "~" (effects (font (size 1.27 1.27))))
          (number "2" (effects (font (size 1.27 1.27))))
        )
      )
    )
	(symbol "R_10k_0402_1" (pin_numbers hide) (pin_names hide) (in_bom yes) (on_board yes)
      (property "Reference" "R" (at 20.32 -5.08 0)
        (effects (font (size 1.27 1.27) (thickness 0.15)) (justify left bottom))
      )
      (property "Value" "R_10k_0402" (at 20.32 -12.7 0)
        (effects (font (size 1.27 1.27) (thickness 0.15)) (justify left bottom) hide)
      )
      (property "Footprint" "antmicro-footprints:R_0402_1005Metric" (at 20.32 -15.24 0)
        (effects (font (size 1.27 1.27) (thickness 0.15)) (justify left bottom) hide)
      )
      (property "Datasheet" "https://www.bourns.com/docs/product-datasheets/cr.pdf" (at 20.32 -17.78 0)
        (effects (font (size 1.27 1.27) (thickness 0.15)) (justify left bottom) hide)
      )
      (property "MPN" "CR0402-FX-1002GLF" (at 20.32 -20.32 0)
        (effects (font (size 1.27 1.27) (thickness 0.15)) (justify left bottom) hide)
      )
      (property "Manufacturer" "Bourns" (at 20.32 -22.86 0)
        (effects (font (size 1.27 1.27) (thickness 0.15)) (justify left bottom) hide)
      )
      (property "License" "Apache-2.0" (at 20.32 -25.4 0)
        (effects (font (size 1.27 1.27) (thickness 0.15)) (justify left bottom) hide)
      )
      (property "Author" "Antmicro" (at 20.32 -27.94 0)
        (effects (font (size 1.27 1.27) (thickness 0.15)) (justify left bottom) hide)
      )
      (property "Val" "10k" (at 20.32 -7.62 0)
        (effects (font (size 1.27 1.27) (thickness 0.15)) (justify left bottom))
      )
      (property "Tolerance" "1%" (at 20.32 -10.16 0)
        (effects (font (size 1.27 1.27)) (justify left bottom) hide)
      )
      (property "ki_keywords" "0402, SMT, RESISTOR, PASSIVE" (at 0 0 0)
        (effects (font (size 1.27 1.27)) hide)
      )
      (property "ki_description" "SMD Chip Resistor, 10 kohm, ± 1%, 62.5 mW, 0402 [1005 Metric], Thick Film, General Purpose" (at 0 0 0)
        (effects (font (size 1.27 1.27)) hide)
      )
      (symbol "R_10k_0402_1_0_1"
        (rectangle (start 0.635 0.889) (end 4.445 -0.889)
          (stroke (width 0.254) (type default))
          (fill (type none))
        )
      )
      (symbol "R_10k_0402_1_1_1"
        (pin passive line (at 0 0 0) (length 0.635)
          (name "~" (effects (font (size 1.27 1.27))))
          (number "1" (effects (font (size 1.27 1.27))))
        )
        (pin passive line (at 5.08 0 180) (length 0.635)
          (name "~" (effects (font (size 1.27 1.27))))
          (number "2" (effects (font (size 1.27 1.27))))
        )
      )
    )
	(symbol "R_10k_0402_2" (pin_numbers hide) (pin_names hide) (in_bom yes) (on_board yes)
      (property "Reference" "R" (at 20.32 -5.08 0)
        (effects (font (size 1.27 1.27) (thickness 0.15)) (justify left bottom))
      )
      (property "Value" "R_10k_0402" (at 20.32 -12.7 0)
        (effects (font (size 1.27 1.27) (thickness 0.15)) (justify left bottom) hide)
      )
      (property "Footprint" "antmicro-footprints:R_0402_1005Metric" (at 20.32 -15.24 0)
        (effects (font (size 1.27 1.27) (thickness 0.15)) (justify left bottom) hide)
      )
      (property "Datasheet" "https://www.bourns.com/docs/product-datasheets/cr.pdf" (at 20.32 -17.78 0)
        (effects (font (size 1.27 1.27) (thickness 0.15)) (justify left bottom) hide)
      )
      (property "MPN" "CR0402-FX-1002GLF" (at 20.32 -20.32 0)
        (effects (font (size 1.27 1.27) (thickness 0.15)) (justify left bottom) hide)
      )
      (property "Manufacturer" "Bourns" (at 20.32 -22.86 0)
        (effects (font (size 1.27 1.27) (thickness 0.15)) (justify left bottom) hide)
      )
      (property "License" "Apache-2.0" (at 20.32 -25.4 0)
        (effects (font (size 1.27 1.27) (thickness 0.15)) (justify left bottom) hide)
      )
      (property "Author" "Antmicro" (at 20.32 -27.94 0)
        (effects (font (size 1.27 1.27) (thickness 0.15)) (justify left bottom) hide)
      )
      (property "Val" "10k" (at 20.32 -7.62 0)
        (effects (font (size 1.27 1.27) (thickness 0.15)) (justify left bottom))
      )
      (property "Tolerance" "1%" (at 20.32 -10.16 0)
        (effects (font (size 1.27 1.27)) (justify left bottom) hide)
      )
      (property "ki_keywords" "0402, SMT, RESISTOR, PASSIVE" (at 0 0 0)
        (effects (font (size 1.27 1.27)) hide)
      )
      (property "ki_description" "SMD Chip Resistor, 10 kohm, ± 1%, 62.5 mW, 0402 [1005 Metric], Thick Film, General Purpose" (at 0 0 0)
        (effects (font (size 1.27 1.27)) hide)
      )
      (symbol "R_10k_0402_2_0_1"
        (rectangle (start 0.635 0.889) (end 4.445 -0.889)
          (stroke (width 0.254) (type default))
          (fill (type none))
        )
      )
      (symbol "R_10k_0402_2_1_1"
        (pin passive line (at 0 0 0) (length 0.635)
          (name "~" (effects (font (size 1.27 1.27))))
          (number "1" (effects (font (size 1.27 1.27))))
        )
        (pin passive line (at 5.08 0 180) (length 0.635)
          (name "~" (effects (font (size 1.27 1.27))))
          (number "2" (effects (font (size 1.27 1.27))))
        )
      )
    )
	(symbol "R_2R_0402_1" (pin_numbers hide) (pin_names hide) (in_bom yes) (on_board yes)
      (property "Reference" "R" (at 20.32 -5.08 0)
        (effects (font (size 1.27 1.27) (thickness 0.15)) (justify left bottom))
      )
      (property "Value" "R_2R_0402" (at 20.32 -12.7 0)
        (effects (font (size 1.27 1.27) (thickness 0.15)) (justify left bottom) hide)
      )
      (property "Footprint" "antmicro-footprints:R_0402_1005Metric" (at 20.32 -15.24 0)
        (effects (font (size 1.27 1.27) (thickness 0.15)) (justify left bottom) hide)
      )
      (property "Datasheet" "https://www.bourns.com/docs/product-datasheets/cr.pdf" (at 20.32 -17.78 0)
        (effects (font (size 1.27 1.27) (thickness 0.15)) (justify left bottom) hide)
      )
      (property "MPN" "CR0402-FX-2R00GLF" (at 20.32 -20.32 0)
        (effects (font (size 1.27 1.27) (thickness 0.15)) (justify left bottom) hide)
      )
      (property "Manufacturer" "Bourns" (at 20.32 -22.86 0)
        (effects (font (size 1.27 1.27) (thickness 0.15)) (justify left bottom) hide)
      )
      (property "License" "Apache-2.0" (at 20.32 -25.4 0)
        (effects (font (size 1.27 1.27) (thickness 0.15)) (justify left bottom) hide)
      )
      (property "Author" "Antmicro" (at 20.32 -27.94 0)
        (effects (font (size 1.27 1.27) (thickness 0.15)) (justify left bottom) hide)
      )
      (property "Val" "2R" (at 20.32 -7.62 0)
        (effects (font (size 1.27 1.27) (thickness 0.15)) (justify left bottom))
      )
      (property "Tolerance" "1%" (at 20.32 -10.16 0)
        (effects (font (size 1.27 1.27)) (justify left bottom) hide)
      )
      (property "ki_keywords" "0402, SMT, RESISTOR, PASSIVE" (at 0 0 0)
        (effects (font (size 1.27 1.27)) hide)
      )
      (property "ki_description" "SMD Chip Resistor" (at 0 0 0)
        (effects (font (size 1.27 1.27)) hide)
      )
      (symbol "R_2R_0402_1_0_1"
        (rectangle (start 0.635 0.889) (end 4.445 -0.889)
          (stroke (width 0.254) (type default))
          (fill (type none))
        )
      )
      (symbol "R_2R_0402_1_1_1"
        (pin passive line (at 0 0 0) (length 0.635)
          (name "~" (effects (font (size 1.27 1.27))))
          (number "1" (effects (font (size 1.27 1.27))))
        )
        (pin passive line (at 5.08 0 180) (length 0.635)
          (name "~" (effects (font (size 1.27 1.27))))
          (number "2" (effects (font (size 1.27 1.27))))
        )
      )
    )
	(symbol "R_2R_0402_2" (pin_numbers hide) (pin_names hide) (in_bom yes) (on_board yes)
      (property "Reference" "R" (at 20.32 -5.08 0)
        (effects (font (size 1.27 1.27) (thickness 0.15)) (justify left bottom))
      )
      (property "Value" "R_2R_0402" (at 20.32 -12.7 0)
        (effects (font (size 1.27 1.27) (thickness 0.15)) (justify left bottom) hide)
      )
      (property "Footprint" "antmicro-footprints:R_0402_1005Metric" (at 20.32 -15.24 0)
        (effects (font (size 1.27 1.27) (thickness 0.15)) (justify left bottom) hide)
      )
      (property "Datasheet" "https://www.bourns.com/docs/product-datasheets/cr.pdf" (at 20.32 -17.78 0)
        (effects (font (size 1.27 1.27) (thickness 0.15)) (justify left bottom) hide)
      )
      (property "MPN" "CR0402-FX-2R00GLF" (at 20.32 -20.32 0)
        (effects (font (size 1.27 1.27) (thickness 0.15)) (justify left bottom) hide)
      )
      (property "Manufacturer" "Bourns" (at 20.32 -22.86 0)
        (effects (font (size 1.27 1.27) (thickness 0.15)) (justify left bottom) hide)
      )
      (property "License" "Apache-2.0" (at 20.32 -25.4 0)
        (effects (font (size 1.27 1.27) (thickness 0.15)) (justify left bottom) hide)
      )
      (property "Author" "Antmicro" (at 20.32 -27.94 0)
        (effects (font (size 1.27 1.27) (thickness 0.15)) (justify left bottom) hide)
      )
      (property "Val" "2R" (at 20.32 -7.62 0)
        (effects (font (size 1.27 1.27) (thickness 0.15)) (justify left bottom))
      )
      (property "Tolerance" "1%" (at 20.32 -10.16 0)
        (effects (font (size 1.27 1.27)) (justify left bottom) hide)
      )
      (property "ki_keywords" "0402, SMT, RESISTOR, PASSIVE" (at 0 0 0)
        (effects (font (size 1.27 1.27)) hide)
      )
      (property "ki_description" "SMD Chip Resistor" (at 0 0 0)
        (effects (font (size 1.27 1.27)) hide)
      )
      (symbol "R_2R_0402_2_0_1"
        (rectangle (start 0.635 0.889) (end 4.445 -0.889)
          (stroke (width 0.254) (type default))
          (fill (type none))
        )
      )
      (symbol "R_2R_0402_2_1_1"
        (pin passive line (at 0 0 0) (length 0.635)
          (name "~" (effects (font (size 1.27 1.27))))
          (number "1" (effects (font (size 1.27 1.27))))
        )
        (pin passive line (at 5.08 0 180) (length 0.635)
          (name "~" (effects (font (size 1.27 1.27))))
          (number "2" (effects (font (size 1.27 1.27))))
        )
      )
    )
	(symbol "R_4k7_0402_1" (pin_numbers hide) (pin_names hide) (in_bom yes) (on_board yes)
      (property "Reference" "R" (at 20.32 -5.08 0)
        (effects (font (size 1.27 1.27) (thickness 0.15)) (justify left bottom))
      )
      (property "Value" "R_4k7_0402" (at 20.32 -12.7 0)
        (effects (font (size 1.27 1.27) (thickness 0.15)) (justify left bottom) hide)
      )
      (property "Footprint" "antmicro-footprints:R_0402_1005Metric" (at 20.32 -15.24 0)
        (effects (font (size 1.27 1.27) (thickness 0.15)) (justify left bottom) hide)
      )
      (property "Datasheet" "https://www.bourns.com/docs/product-datasheets/cr.pdf" (at 20.32 -17.78 0)
        (effects (font (size 1.27 1.27) (thickness 0.15)) (justify left bottom) hide)
      )
      (property "MPN" "CR0402-FX-4701GLF" (at 20.32 -20.32 0)
        (effects (font (size 1.27 1.27) (thickness 0.15)) (justify left bottom) hide)
      )
      (property "Manufacturer" "Bourns" (at 20.32 -22.86 0)
        (effects (font (size 1.27 1.27) (thickness 0.15)) (justify left bottom) hide)
      )
      (property "License" "Apache-2.0" (at 20.32 -25.4 0)
        (effects (font (size 1.27 1.27) (thickness 0.15)) (justify left bottom) hide)
      )
      (property "Author" "Antmicro" (at 20.32 -27.94 0)
        (effects (font (size 1.27 1.27) (thickness 0.15)) (justify left bottom) hide)
      )
      (property "Val" "4k7" (at 20.32 -7.62 0)
        (effects (font (size 1.27 1.27) (thickness 0.15)) (justify left bottom))
      )
      (property "Tolerance" "1%" (at 20.32 -10.16 0)
        (effects (font (size 1.27 1.27)) (justify left bottom) hide)
      )
      (property "ki_keywords" "0402, SMT, RESISTOR, PASSIVE" (at 0 0 0)
        (effects (font (size 1.27 1.27)) hide)
      )
      (property "ki_description" "SMD Chip Resistor, 4.7 kohm, ± 1%, 62.5 mW, 0402 [1005 Metric], Thick Film, General Purpose" (at 0 0 0)
        (effects (font (size 1.27 1.27)) hide)
      )
      (symbol "R_4k7_0402_1_0_1"
        (rectangle (start 0.635 0.889) (end 4.445 -0.889)
          (stroke (width 0.254) (type default))
          (fill (type none))
        )
      )
      (symbol "R_4k7_0402_1_1_1"
        (pin passive line (at 0 0 0) (length 0.635)
          (name "~" (effects (font (size 1.27 1.27))))
          (number "1" (effects (font (size 1.27 1.27))))
        )
        (pin passive line (at 5.08 0 180) (length 0.635)
          (name "~" (effects (font (size 1.27 1.27))))
          (number "2" (effects (font (size 1.27 1.27))))
        )
      )
    )
	(symbol "R_4k7_0402_2" (pin_numbers hide) (pin_names hide) (in_bom yes) (on_board yes)
      (property "Reference" "R" (at 20.32 -5.08 0)
        (effects (font (size 1.27 1.27) (thickness 0.15)) (justify left bottom))
      )
      (property "Value" "R_4k7_0402" (at 20.32 -12.7 0)
        (effects (font (size 1.27 1.27) (thickness 0.15)) (justify left bottom) hide)
      )
      (property "Footprint" "antmicro-footprints:R_0402_1005Metric" (at 20.32 -15.24 0)
        (effects (font (size 1.27 1.27) (thickness 0.15)) (justify left bottom) hide)
      )
      (property "Datasheet" "https://www.bourns.com/docs/product-datasheets/cr.pdf" (at 20.32 -17.78 0)
        (effects (font (size 1.27 1.27) (thickness 0.15)) (justify left bottom) hide)
      )
      (property "MPN" "CR0402-FX-4701GLF" (at 20.32 -20.32 0)
        (effects (font (size 1.27 1.27) (thickness 0.15)) (justify left bottom) hide)
      )
      (property "Manufacturer" "Bourns" (at 20.32 -22.86 0)
        (effects (font (size 1.27 1.27) (thickness 0.15)) (justify left bottom) hide)
      )
      (property "License" "Apache-2.0" (at 20.32 -25.4 0)
        (effects (font (size 1.27 1.27) (thickness 0.15)) (justify left bottom) hide)
      )
      (property "Author" "Antmicro" (at 20.32 -27.94 0)
        (effects (font (size 1.27 1.27) (thickness 0.15)) (justify left bottom) hide)
      )
      (property "Val" "4k7" (at 20.32 -7.62 0)
        (effects (font (size 1.27 1.27) (thickness 0.15)) (justify left bottom))
      )
      (property "Tolerance" "1%" (at 20.32 -10.16 0)
        (effects (font (size 1.27 1.27)) (justify left bottom) hide)
      )
      (property "ki_keywords" "0402, SMT, RESISTOR, PASSIVE" (at 0 0 0)
        (effects (font (size 1.27 1.27)) hide)
      )
      (property "ki_description" "SMD Chip Resistor, 4.7 kohm, ± 1%, 62.5 mW, 0402 [1005 Metric], Thick Film, General Purpose" (at 0 0 0)
        (effects (font (size 1.27 1.27)) hide)
      )
      (symbol "R_4k7_0402_2_0_1"
        (rectangle (start 0.635 0.889) (end 4.445 -0.889)
          (stroke (width 0.254) (type default))
          (fill (type none))
        )
      )
      (symbol "R_4k7_0402_2_1_1"
        (pin passive line (at 0 0 0) (length 0.635)
          (name "~" (effects (font (size 1.27 1.27))))
          (number "1" (effects (font (size 1.27 1.27))))
        )
        (pin passive line (at 5.08 0 180) (length 0.635)
          (name "~" (effects (font (size 1.27 1.27))))
          (number "2" (effects (font (size 1.27 1.27))))
        )
      )
    )
	(symbol "R_4k7_0402_3" (pin_numbers hide) (pin_names hide) (in_bom yes) (on_board yes)
      (property "Reference" "R" (at 20.32 -5.08 0)
        (effects (font (size 1.27 1.27) (thickness 0.15)) (justify left bottom))
      )
      (property "Value" "R_4k7_0402" (at 20.32 -12.7 0)
        (effects (font (size 1.27 1.27) (thickness 0.15)) (justify left bottom) hide)
      )
      (property "Footprint" "antmicro-footprints:R_0402_1005Metric" (at 20.32 -15.24 0)
        (effects (font (size 1.27 1.27) (thickness 0.15)) (justify left bottom) hide)
      )
      (property "Datasheet" "https://www.bourns.com/docs/product-datasheets/cr.pdf" (at 20.32 -17.78 0)
        (effects (font (size 1.27 1.27) (thickness 0.15)) (justify left bottom) hide)
      )
      (property "MPN" "CR0402-FX-4701GLF" (at 20.32 -20.32 0)
        (effects (font (size 1.27 1.27) (thickness 0.15)) (justify left bottom) hide)
      )
      (property "Manufacturer" "Bourns" (at 20.32 -22.86 0)
        (effects (font (size 1.27 1.27) (thickness 0.15)) (justify left bottom) hide)
      )
      (property "License" "Apache-2.0" (at 20.32 -25.4 0)
        (effects (font (size 1.27 1.27) (thickness 0.15)) (justify left bottom) hide)
      )
      (property "Author" "Antmicro" (at 20.32 -27.94 0)
        (effects (font (size 1.27 1.27) (thickness 0.15)) (justify left bottom) hide)
      )
      (property "Val" "4k7" (at 20.32 -7.62 0)
        (effects (font (size 1.27 1.27) (thickness 0.15)) (justify left bottom))
      )
      (property "Tolerance" "1%" (at 20.32 -10.16 0)
        (effects (font (size 1.27 1.27)) (justify left bottom) hide)
      )
      (property "ki_keywords" "0402, SMT, RESISTOR, PASSIVE" (at 0 0 0)
        (effects (font (size 1.27 1.27)) hide)
      )
      (property "ki_description" "SMD Chip Resistor, 4.7 kohm, ± 1%, 62.5 mW, 0402 [1005 Metric], Thick Film, General Purpose" (at 0 0 0)
        (effects (font (size 1.27 1.27)) hide)
      )
      (symbol "R_4k7_0402_3_0_1"
        (rectangle (start 0.635 0.889) (end 4.445 -0.889)
          (stroke (width 0.254) (type default))
          (fill (type none))
        )
      )
      (symbol "R_4k7_0402_3_1_1"
        (pin passive line (at 0 0 0) (length 0.635)
          (name "~" (effects (font (size 1.27 1.27))))
          (number "1" (effects (font (size 1.27 1.27))))
        )
        (pin passive line (at 5.08 0 180) (length 0.635)
          (name "~" (effects (font (size 1.27 1.27))))
          (number "2" (effects (font (size 1.27 1.27))))
        )
      )
    )
	(symbol "R_5k1_0402_1" (pin_numbers hide) (pin_names hide) (in_bom yes) (on_board yes)
      (property "Reference" "R" (at 20.32 -5.08 0)
        (effects (font (size 1.27 1.27) (thickness 0.15)) (justify left bottom))
      )
      (property "Value" "R_5k1_0402" (at 20.32 -12.7 0)
        (effects (font (size 1.27 1.27) (thickness 0.15)) (justify left bottom) hide)
      )
      (property "Footprint" "antmicro-footprints:R_0402_1005Metric" (at 20.32 -15.24 0)
        (effects (font (size 1.27 1.27) (thickness 0.15)) (justify left bottom) hide)
      )
      (property "Datasheet" "https://www.bourns.com/docs/product-datasheets/cr.pdf" (at 20.32 -17.78 0)
        (effects (font (size 1.27 1.27) (thickness 0.15)) (justify left bottom) hide)
      )
      (property "MPN" "CR0402-FX-5101GLF" (at 20.32 -20.32 0)
        (effects (font (size 1.27 1.27) (thickness 0.15)) (justify left bottom) hide)
      )
      (property "Manufacturer" "Bourns" (at 20.32 -22.86 0)
        (effects (font (size 1.27 1.27) (thickness 0.15)) (justify left bottom) hide)
      )
      (property "License" "Apache-2.0" (at 20.32 -25.4 0)
        (effects (font (size 1.27 1.27) (thickness 0.15)) (justify left bottom) hide)
      )
      (property "Author" "Antmicro" (at 20.32 -27.94 0)
        (effects (font (size 1.27 1.27) (thickness 0.15)) (justify left bottom) hide)
      )
      (property "Val" "5k1" (at 20.32 -7.62 0)
        (effects (font (size 1.27 1.27) (thickness 0.15)) (justify left bottom))
      )
      (property "Tolerance" "1%" (at 20.32 -10.16 0)
        (effects (font (size 1.27 1.27)) (justify left bottom) hide)
      )
      (property "ki_keywords" "0402, SMT, RESISTOR, PASSIVE" (at 0 0 0)
        (effects (font (size 1.27 1.27)) hide)
      )
      (property "ki_description" "SMD Chip Resistor, 5.1 kohm, ± 1%, 63 mW, 0402 [1005 Metric], Thick Film, General Purpose" (at 0 0 0)
        (effects (font (size 1.27 1.27)) hide)
      )
      (symbol "R_5k1_0402_1_0_1"
        (rectangle (start 0.635 0.889) (end 4.445 -0.889)
          (stroke (width 0.254) (type default))
          (fill (type none))
        )
      )
      (symbol "R_5k1_0402_1_1_1"
        (pin passive line (at 0 0 0) (length 0.635)
          (name "~" (effects (font (size 1.27 1.27))))
          (number "1" (effects (font (size 1.27 1.27))))
        )
        (pin passive line (at 5.08 0 180) (length 0.635)
          (name "~" (effects (font (size 1.27 1.27))))
          (number "2" (effects (font (size 1.27 1.27))))
        )
      )
    )
	(symbol "SI7613DN-T1-GE3_1" (pin_names (offset 0)) (in_bom yes) (on_board yes)
      (property "Reference" "Q" (at 15.24 5.08 0)
        (effects (font (size 1.27 1.27) (thickness 0.15)) (justify left bottom))
      )
      (property "Value" "SI7613DN-T1-GE3" (at 15.24 2.54 0)
        (effects (font (size 1.27 1.27) (thickness 0.15)) (justify left bottom) hide)
      )
      (property "Footprint" "antmicro-footprints:Vishay_PowerPAK_1212-8_Single" (at 15.24 1.27 0)
        (effects (font (size 1.27 1.27) (thickness 0.15)) (justify left bottom) hide)
      )
      (property "Datasheet" "https://www.vishay.com/docs/64809/si7613dn.pdf" (at 15.24 -1.27 0)
        (effects (font (size 1.27 1.27) (thickness 0.15)) (justify left bottom) hide)
      )
      (property "MPN" "SI7613DN-T1-GE3" (at 15.24 -5.08 0)
        (effects (font (size 1.27 1.27) (thickness 0.15)) (justify left bottom))
      )
      (property "Manufacturer" "Vishay" (at 15.24 -7.62 0)
        (effects (font (size 1.27 1.27) (thickness 0.15)) (justify left bottom) hide)
      )
      (property "Author" "Antmicro" (at 15.24 -10.16 0)
        (effects (font (size 1.27 1.27) (thickness 0.15)) (justify left bottom) hide)
      )
      (property "License" "Apache-2.0" (at 15.24 -12.7 0)
        (effects (font (size 1.27 1.27) (thickness 0.15)) (justify left bottom) hide)
      )
      (property "ki_keywords" "SMT, TRANSISTOR, SEMICONDUCTOR, MOSFET, PMOS" (at 0 0 0)
        (effects (font (size 1.27 1.27)) hide)
      )
      (property "ki_description" "Power MOSFET, P Channel, 20 V, 35 A, 0.0072 ohm, PowerPAK 1212, Surface Mount" (at 0 0 0)
        (effects (font (size 1.27 1.27)) hide)
      )
      (symbol "SI7613DN-T1-GE3_1_1_1"
        (polyline
          (pts
            (xy 5.08 1.143)
            (xy 5.08 0.635)
          )
          (stroke (width 0.254) (type default))
          (fill (type background))
        )
        (polyline
          (pts
            (xy 5.08 1.143)
            (xy 5.08 1.651)
          )
          (stroke (width 0.254) (type default))
          (fill (type background))
        )
        (polyline
          (pts
            (xy 5.08 2.54)
            (xy 5.08 2.032)
          )
          (stroke (width 0.254) (type default))
          (fill (type background))
        )
        (polyline
          (pts
            (xy 5.08 2.54)
            (xy 5.08 3.048)
          )
          (stroke (width 0.254) (type default))
          (fill (type background))
        )
        (polyline
          (pts
            (xy 5.08 4.445)
            (xy 5.08 3.429)
          )
          (stroke (width 0.254) (type default))
          (fill (type background))
        )
        (polyline
          (pts
            (xy 7.62 1.143)
            (xy 5.08 1.143)
          )
          (stroke (width 0.254) (type default))
          (fill (type background))
        )
        (polyline
          (pts
            (xy 9.144 2.2352)
            (xy 8.128 2.2352)
          )
          (stroke (width 0.254) (type default))
          (fill (type background))
        )
        (polyline
          (pts
            (xy 2.54 0)
            (xy 4.572 0)
            (xy 4.572 3.937)
          )
          (stroke (width 0.254) (type default))
          (fill (type none))
        )
        (polyline
          (pts
            (xy 7.62 -1.27)
            (xy 7.62 2.54)
            (xy 5.08 2.54)
          )
          (stroke (width 0.254) (type default))
          (fill (type none))
        )
        (polyline
          (pts
            (xy 7.62 6.35)
            (xy 7.62 3.937)
            (xy 5.08 3.937)
          )
          (stroke (width 0.254) (type default))
          (fill (type none))
        )
        (polyline
          (pts
            (xy 7.239 2.54)
            (xy 6.477 3.048)
            (xy 6.477 2.032)
            (xy 7.239 2.54)
          )
          (stroke (width 0.254) (type default))
          (fill (type outline))
        )
        (polyline
          (pts
            (xy 8.636 2.286)
            (xy 8.128 3.048)
            (xy 9.144 3.048)
            (xy 8.636 2.286)
          )
          (stroke (width 0.254) (type default))
          (fill (type outline))
        )
        (polyline
          (pts
            (xy 7.493 0.635)
            (xy 8.636 0.635)
            (xy 8.636 3.937)
            (xy 8.636 4.445)
            (xy 7.493 4.445)
          )
          (stroke (width 0.254) (type default))
          (fill (type background))
        )
        (circle (center 6.35 2.54) (radius 3.302)
          (stroke (width 0.254) (type default))
          (fill (type background))
        )
        (circle (center 7.62 0.635) (radius 0.127)
          (stroke (width 0.254) (type default))
          (fill (type background))
        )
        (circle (center 7.62 1.143) (radius 0.127)
          (stroke (width 0.254) (type default))
          (fill (type background))
        )
        (circle (center 7.62 4.445) (radius 0.127)
          (stroke (width 0.254) (type default))
          (fill (type background))
        )
        (pin passive line (at 7.62 -3.81 90) (length 2.54)
          (name "S" (effects (font (size 1.27 1.27))))
          (number "1" (effects (font (size 1.27 1.27))))
        )
        (pin passive line (at 7.62 -3.81 90) (length 2.54) hide
          (name "S" (effects (font (size 1.27 1.27))))
          (number "2" (effects (font (size 1.27 1.27))))
        )
        (pin passive line (at 7.62 -3.81 90) (length 2.54) hide
          (name "S" (effects (font (size 1.27 1.27))))
          (number "3" (effects (font (size 1.27 1.27))))
        )
        (pin passive line (at 0 0 0) (length 2.54)
          (name "G" (effects (font (size 1.27 1.27))))
          (number "4" (effects (font (size 1.27 1.27))))
        )
        (pin passive line (at 7.62 8.89 270) (length 2.54)
          (name "D" (effects (font (size 1.27 1.27))))
          (number "5" (effects (font (size 1.27 1.27))))
        )
      )
    )
	(symbol "SI7613DN-T1-GE3_2" (pin_names (offset 0)) (in_bom yes) (on_board yes)
      (property "Reference" "Q" (at 15.24 5.08 0)
        (effects (font (size 1.27 1.27) (thickness 0.15)) (justify left bottom))
      )
      (property "Value" "SI7613DN-T1-GE3" (at 15.24 2.54 0)
        (effects (font (size 1.27 1.27) (thickness 0.15)) (justify left bottom) hide)
      )
      (property "Footprint" "antmicro-footprints:Vishay_PowerPAK_1212-8_Single" (at 15.24 1.27 0)
        (effects (font (size 1.27 1.27) (thickness 0.15)) (justify left bottom) hide)
      )
      (property "Datasheet" "https://www.vishay.com/docs/64809/si7613dn.pdf" (at 15.24 -1.27 0)
        (effects (font (size 1.27 1.27) (thickness 0.15)) (justify left bottom) hide)
      )
      (property "MPN" "SI7613DN-T1-GE3" (at 15.24 -5.08 0)
        (effects (font (size 1.27 1.27) (thickness 0.15)) (justify left bottom))
      )
      (property "Manufacturer" "Vishay" (at 15.24 -7.62 0)
        (effects (font (size 1.27 1.27) (thickness 0.15)) (justify left bottom) hide)
      )
      (property "Author" "Antmicro" (at 15.24 -10.16 0)
        (effects (font (size 1.27 1.27) (thickness 0.15)) (justify left bottom) hide)
      )
      (property "License" "Apache-2.0" (at 15.24 -12.7 0)
        (effects (font (size 1.27 1.27) (thickness 0.15)) (justify left bottom) hide)
      )
      (property "ki_keywords" "SMT, TRANSISTOR, SEMICONDUCTOR, MOSFET, PMOS" (at 0 0 0)
        (effects (font (size 1.27 1.27)) hide)
      )
      (property "ki_description" "Power MOSFET, P Channel, 20 V, 35 A, 0.0072 ohm, PowerPAK 1212, Surface Mount" (at 0 0 0)
        (effects (font (size 1.27 1.27)) hide)
      )
      (symbol "SI7613DN-T1-GE3_2_1_1"
        (polyline
          (pts
            (xy 5.08 1.143)
            (xy 5.08 0.635)
          )
          (stroke (width 0.254) (type default))
          (fill (type background))
        )
        (polyline
          (pts
            (xy 5.08 1.143)
            (xy 5.08 1.651)
          )
          (stroke (width 0.254) (type default))
          (fill (type background))
        )
        (polyline
          (pts
            (xy 5.08 2.54)
            (xy 5.08 2.032)
          )
          (stroke (width 0.254) (type default))
          (fill (type background))
        )
        (polyline
          (pts
            (xy 5.08 2.54)
            (xy 5.08 3.048)
          )
          (stroke (width 0.254) (type default))
          (fill (type background))
        )
        (polyline
          (pts
            (xy 5.08 4.445)
            (xy 5.08 3.429)
          )
          (stroke (width 0.254) (type default))
          (fill (type background))
        )
        (polyline
          (pts
            (xy 7.62 1.143)
            (xy 5.08 1.143)
          )
          (stroke (width 0.254) (type default))
          (fill (type background))
        )
        (polyline
          (pts
            (xy 9.144 2.2352)
            (xy 8.128 2.2352)
          )
          (stroke (width 0.254) (type default))
          (fill (type background))
        )
        (polyline
          (pts
            (xy 2.54 0)
            (xy 4.572 0)
            (xy 4.572 3.937)
          )
          (stroke (width 0.254) (type default))
          (fill (type none))
        )
        (polyline
          (pts
            (xy 7.62 -1.27)
            (xy 7.62 2.54)
            (xy 5.08 2.54)
          )
          (stroke (width 0.254) (type default))
          (fill (type none))
        )
        (polyline
          (pts
            (xy 7.62 6.35)
            (xy 7.62 3.937)
            (xy 5.08 3.937)
          )
          (stroke (width 0.254) (type default))
          (fill (type none))
        )
        (polyline
          (pts
            (xy 7.239 2.54)
            (xy 6.477 3.048)
            (xy 6.477 2.032)
            (xy 7.239 2.54)
          )
          (stroke (width 0.254) (type default))
          (fill (type outline))
        )
        (polyline
          (pts
            (xy 8.636 2.286)
            (xy 8.128 3.048)
            (xy 9.144 3.048)
            (xy 8.636 2.286)
          )
          (stroke (width 0.254) (type default))
          (fill (type outline))
        )
        (polyline
          (pts
            (xy 7.493 0.635)
            (xy 8.636 0.635)
            (xy 8.636 3.937)
            (xy 8.636 4.445)
            (xy 7.493 4.445)
          )
          (stroke (width 0.254) (type default))
          (fill (type background))
        )
        (circle (center 6.35 2.54) (radius 3.302)
          (stroke (width 0.254) (type default))
          (fill (type background))
        )
        (circle (center 7.62 0.635) (radius 0.127)
          (stroke (width 0.254) (type default))
          (fill (type background))
        )
        (circle (center 7.62 1.143) (radius 0.127)
          (stroke (width 0.254) (type default))
          (fill (type background))
        )
        (circle (center 7.62 4.445) (radius 0.127)
          (stroke (width 0.254) (type default))
          (fill (type background))
        )
        (pin passive line (at 7.62 -3.81 90) (length 2.54)
          (name "S" (effects (font (size 1.27 1.27))))
          (number "1" (effects (font (size 1.27 1.27))))
        )
        (pin passive line (at 7.62 -3.81 90) (length 2.54) hide
          (name "S" (effects (font (size 1.27 1.27))))
          (number "2" (effects (font (size 1.27 1.27))))
        )
        (pin passive line (at 7.62 -3.81 90) (length 2.54) hide
          (name "S" (effects (font (size 1.27 1.27))))
          (number "3" (effects (font (size 1.27 1.27))))
        )
        (pin passive line (at 0 0 0) (length 2.54)
          (name "G" (effects (font (size 1.27 1.27))))
          (number "4" (effects (font (size 1.27 1.27))))
        )
        (pin passive line (at 7.62 8.89 270) (length 2.54)
          (name "D" (effects (font (size 1.27 1.27))))
          (number "5" (effects (font (size 1.27 1.27))))
        )
      )
    )
	(symbol "TMCS1100A2-Q1_1" (in_bom yes) (on_board yes)
      (property "Reference" "U" (at 33.02 -2.54 0)
        (effects (font (size 1.27 1.27) (thickness 0.15)) (justify left bottom))
      )
      (property "Value" "TMCS1100A2-Q1" (at 33.02 -7.62 0)
        (effects (font (size 1.27 1.27) (thickness 0.15)) (justify left bottom) hide)
      )
      (property "Footprint" "antmicro-footprints:SOIC-8_3.9x4.9x1.75mm_P1.27mm" (at 33.02 -10.16 0)
        (effects (font (size 1.27 1.27) (thickness 0.15)) (justify left bottom) hide)
      )
      (property "Datasheet" "https://www.ti.com/lit/ds/symlink/tmcs1100-q1.pdf?ts=1647195769204&ref_url=https%253A%252F%252Fwww.mouser.de%252F" (at 33.02 -12.7 0)
        (effects (font (size 1.27 1.27) (thickness 0.15)) (justify left bottom) hide)
      )
      (property "MPN" "TMCS1100A2QDRQ1" (at 33.02 -5.08 0)
        (effects (font (size 1.27 1.27) (thickness 0.15)) (justify left bottom))
      )
      (property "Manufacturer" "Texas Instruments" (at 33.02 -15.24 0)
        (effects (font (size 1.27 1.27) (thickness 0.15)) (justify left bottom) hide)
      )
      (property "Author" "Antmicro" (at 33.02 -17.78 0)
        (effects (font (size 1.27 1.27) (thickness 0.15)) (justify left bottom) hide)
      )
      (property "License" "Apache-2.0" (at 33.02 -20.32 0)
        (effects (font (size 1.27 1.27) (thickness 0.15)) (justify left bottom) hide)
      )
      (property "ki_keywords" "SMT, SENSOR, IC, POWER" (at 0 0 0)
        (effects (font (size 1.27 1.27)) hide)
      )
      (property "ki_description" "Hall current Sensor/transducer" (at 0 0 0)
        (effects (font (size 1.27 1.27)) hide)
      )
      (symbol "TMCS1100A2-Q1_1_0_1"
        (rectangle (start 2.54 2.54) (end 15.24 -7.62)
          (stroke (width 0.254) (type default))
          (fill (type background))
        )
      )
      (symbol "TMCS1100A2-Q1_1_1_1"
        (pin input line (at 0 -2.54 0) (length 2.54)
          (name "IN+" (effects (font (size 1.27 1.27))))
          (number "1" (effects (font (size 1.27 1.27))))
        )
        (pin input line (at 0 -2.54 0) (length 2.54) hide
          (name "IN+" (effects (font (size 1.27 1.27))))
          (number "2" (effects (font (size 1.27 1.27))))
        )
        (pin input line (at 0 -5.08 0) (length 2.54)
          (name "IN-" (effects (font (size 1.27 1.27))))
          (number "3" (effects (font (size 1.27 1.27))))
        )
        (pin input line (at 0 -5.08 0) (length 2.54) hide
          (name "IN-" (effects (font (size 1.27 1.27))))
          (number "4" (effects (font (size 1.27 1.27))))
        )
        (pin power_in line (at 17.78 -5.08 180) (length 2.54)
          (name "GND" (effects (font (size 1.27 1.27))))
          (number "5" (effects (font (size 1.27 1.27))))
        )
        (pin input line (at 17.78 -2.54 180) (length 2.54)
          (name "VREF" (effects (font (size 1.27 1.27))))
          (number "6" (effects (font (size 1.27 1.27))))
        )
        (pin output line (at 17.78 0 180) (length 2.54)
          (name "VOUT" (effects (font (size 1.27 1.27))))
          (number "7" (effects (font (size 1.27 1.27))))
        )
        (pin power_in line (at 0 0 0) (length 2.54)
          (name "VCC" (effects (font (size 1.27 1.27))))
          (number "8" (effects (font (size 1.27 1.27))))
        )
      )
    )
	(symbol "antmicroCapacitors0402:C_100n_0402" (pin_numbers hide) (pin_names hide) (in_bom yes) (on_board yes)
      (property "Reference" "C" (at 20.32 -5.08 0)
        (effects (font (size 1.27 1.27) (thickness 0.15)) (justify left bottom))
      )
      (property "Value" "C_100n_0402" (at 20.32 -10.16 0)
        (effects (font (size 1.27 1.27) (thickness 0.15)) (justify left bottom) hide)
      )
      (property "Footprint" "antmicro-footprints:C_0402_1005Metric" (at 20.32 -12.7 0)
        (effects (font (size 1.27 1.27) (thickness 0.15)) (justify left bottom) hide)
      )
      (property "Datasheet" "https://www.murata.com/products/productdetail?partno=GRM155R61H104KE14%23" (at 20.32 -15.24 0)
        (effects (font (size 1.27 1.27) (thickness 0.15)) (justify left bottom) hide)
      )
      (property "MPN" "GRM155R61H104KE14D" (at 20.32 -17.78 0)
        (effects (font (size 1.27 1.27) (thickness 0.15)) (justify left bottom) hide)
      )
      (property "Manufacturer" "Murata" (at 20.32 -20.32 0)
        (effects (font (size 1.27 1.27) (thickness 0.15)) (justify left bottom) hide)
      )
      (property "License" "Apache-2.0" (at 20.32 -22.86 0)
        (effects (font (size 1.27 1.27) (thickness 0.15)) (justify left bottom) hide)
      )
      (property "Author" "Antmicro" (at 20.32 -25.4 0)
        (effects (font (size 1.27 1.27) (thickness 0.15)) (justify left bottom) hide)
      )
      (property "Val" "100n" (at 20.32 -7.62 0)
        (effects (font (size 1.27 1.27) (thickness 0.15)) (justify left bottom))
      )
      (property "Voltage" "50V" (at 20.32 -27.94 0)
        (effects (font (size 1.27 1.27)) (justify left bottom) hide)
      )
      (property "Dielectric" "X5R" (at 20.32 -30.48 0)
        (effects (font (size 1.27 1.27)) (justify left bottom) hide)
      )
      (property "ki_keywords" "0402, SMT, CAPACITOR, PASSIVE, CERAMIC, MLCC" (at 0 0 0)
        (effects (font (size 1.27 1.27)) hide)
      )
      (property "ki_description" "SMD Multilayer Ceramic Capacitor, 0.1 µF, 50 V, 0402 [1005 Metric], ± 10%, X5R, GRM Series" (at 0 0 0)
        (effects (font (size 1.27 1.27)) hide)
      )
      (symbol "C_100n_0402_0_1"
        (polyline
          (pts
            (xy 2.032 -1.524)
            (xy 2.032 1.524)
          )
          (stroke (width 0.3048) (type default))
          (fill (type none))
        )
        (polyline
          (pts
            (xy 3.048 -1.524)
            (xy 3.048 1.524)
          )
          (stroke (width 0.3302) (type default))
          (fill (type none))
        )
      )
      (symbol "C_100n_0402_1_1"
        (pin passive line (at 0 0 0) (length 2.032)
          (name "~" (effects (font (size 1.27 1.27))))
          (number "1" (effects (font (size 1.27 1.27))))
        )
        (pin passive line (at 5.08 0 180) (length 2.032)
          (name "~" (effects (font (size 1.27 1.27))))
          (number "2" (effects (font (size 1.27 1.27))))
        )
      )
    )
	(symbol "antmicroCapacitors0402:C_18p_0402" (pin_numbers hide) (pin_names hide) (in_bom yes) (on_board yes)
      (property "Reference" "C" (at 20.32 -5.08 0)
        (effects (font (size 1.27 1.27) (thickness 0.15)) (justify left bottom))
      )
      (property "Value" "C_18p_0402" (at 20.32 -10.16 0)
        (effects (font (size 1.27 1.27) (thickness 0.15)) (justify left bottom) hide)
      )
      (property "Footprint" "antmicro-footprints:C_0402_1005Metric" (at 20.32 -12.7 0)
        (effects (font (size 1.27 1.27) (thickness 0.15)) (justify left bottom) hide)
      )
      (property "Datasheet" "https://product.samsungsem.com/mlcc/CL05C180JB51PN.do" (at 20.32 -15.24 0)
        (effects (font (size 1.27 1.27) (thickness 0.15)) (justify left bottom) hide)
      )
      (property "MPN" "CL05C180JB51PNC" (at 20.32 -17.78 0)
        (effects (font (size 1.27 1.27) (thickness 0.15)) (justify left bottom) hide)
      )
      (property "Manufacturer" "Samsung Electro-Mechanics" (at 20.32 -20.32 0)
        (effects (font (size 1.27 1.27) (thickness 0.15)) (justify left bottom) hide)
      )
      (property "License" "Apache-2.0" (at 20.32 -22.86 0)
        (effects (font (size 1.27 1.27) (thickness 0.15)) (justify left bottom) hide)
      )
      (property "Author" "Antmicro" (at 20.32 -25.4 0)
        (effects (font (size 1.27 1.27) (thickness 0.15)) (justify left bottom) hide)
      )
      (property "Val" "18p" (at 20.32 -7.62 0)
        (effects (font (size 1.27 1.27) (thickness 0.15)) (justify left bottom))
      )
      (property "Voltage" "" (at 20.32 -27.94 0)
        (effects (font (size 1.27 1.27)) (justify left bottom) hide)
      )
      (property "Dielectric" "" (at 20.32 -30.48 0)
        (effects (font (size 1.27 1.27)) (justify left bottom) hide)
      )
      (property "ki_keywords" "0402, SMT, CAPACITOR, PASSIVE" (at 0 0 0)
        (effects (font (size 1.27 1.27)) hide)
      )
      (property "ki_description" "SMD Multilayer Ceramic Capacitor, 18 pF, 50 V, 0402 [1005 Metric], ± 5%, C0G / NP0, MC" (at 0 0 0)
        (effects (font (size 1.27 1.27)) hide)
      )
      (symbol "C_18p_0402_0_1"
        (polyline
          (pts
            (xy 2.032 -1.524)
            (xy 2.032 1.524)
          )
          (stroke (width 0.3048) (type default))
          (fill (type none))
        )
        (polyline
          (pts
            (xy 3.048 -1.524)
            (xy 3.048 1.524)
          )
          (stroke (width 0.3302) (type default))
          (fill (type none))
        )
      )
      (symbol "C_18p_0402_1_1"
        (pin passive line (at 0 0 0) (length 2.032)
          (name "~" (effects (font (size 1.27 1.27))))
          (number "1" (effects (font (size 1.27 1.27))))
        )
        (pin passive line (at 5.08 0 180) (length 2.032)
          (name "~" (effects (font (size 1.27 1.27))))
          (number "2" (effects (font (size 1.27 1.27))))
        )
      )
    )
	(symbol "antmicroCapacitors0402:C_1u_0402" (pin_numbers hide) (pin_names hide) (in_bom yes) (on_board yes)
      (property "Reference" "C" (at 20.32 -5.08 0)
        (effects (font (size 1.27 1.27) (thickness 0.15)) (justify left bottom))
      )
      (property "Value" "C_1u_0402" (at 20.32 -10.16 0)
        (effects (font (size 1.27 1.27) (thickness 0.15)) (justify left bottom) hide)
      )
      (property "Footprint" "antmicro-footprints:C_0402_1005Metric" (at 20.32 -12.7 0)
        (effects (font (size 1.27 1.27) (thickness 0.15)) (justify left bottom) hide)
      )
      (property "Datasheet" "https://product.tdk.com/en/search/capacitor/ceramic/mlcc/info?part_no=C1005X6S1A105K050BC" (at 20.32 -15.24 0)
        (effects (font (size 1.27 1.27) (thickness 0.15)) (justify left bottom) hide)
      )
      (property "MPN" "C1005X6S1A105K050BC" (at 20.32 -17.78 0)
        (effects (font (size 1.27 1.27) (thickness 0.15)) (justify left bottom) hide)
      )
      (property "Manufacturer" "TDK" (at 20.32 -20.32 0)
        (effects (font (size 1.27 1.27) (thickness 0.15)) (justify left bottom) hide)
      )
      (property "License" "Apache-2.0" (at 20.32 -22.86 0)
        (effects (font (size 1.27 1.27) (thickness 0.15)) (justify left bottom) hide)
      )
      (property "Author" "Antmicro" (at 20.32 -25.4 0)
        (effects (font (size 1.27 1.27) (thickness 0.15)) (justify left bottom) hide)
      )
      (property "Val" "1u" (at 20.32 -7.62 0)
        (effects (font (size 1.27 1.27) (thickness 0.15)) (justify left bottom))
      )
      (property "Voltage" "" (at 20.32 -27.94 0)
        (effects (font (size 1.27 1.27)) (justify left bottom) hide)
      )
      (property "Dielectric" "" (at 20.32 -30.48 0)
        (effects (font (size 1.27 1.27)) (justify left bottom) hide)
      )
      (property "ki_keywords" "0402, SMT, CAPACITOR, PASSIVE, CERAMIC, MLCC" (at 0 0 0)
        (effects (font (size 1.27 1.27)) hide)
      )
      (property "ki_description" "SMD Multilayer Ceramic Capacitor, 1 µF, 10 V, 0402 [1005 Metric], ± 10%, X6S, C" (at 0 0 0)
        (effects (font (size 1.27 1.27)) hide)
      )
      (symbol "C_1u_0402_0_1"
        (polyline
          (pts
            (xy 2.032 -1.524)
            (xy 2.032 1.524)
          )
          (stroke (width 0.3048) (type default))
          (fill (type none))
        )
        (polyline
          (pts
            (xy 3.048 -1.524)
            (xy 3.048 1.524)
          )
          (stroke (width 0.3302) (type default))
          (fill (type none))
        )
      )
      (symbol "C_1u_0402_1_1"
        (pin passive line (at 0 0 0) (length 2.032)
          (name "~" (effects (font (size 1.27 1.27))))
          (number "1" (effects (font (size 1.27 1.27))))
        )
        (pin passive line (at 5.08 0 180) (length 2.032)
          (name "~" (effects (font (size 1.27 1.27))))
          (number "2" (effects (font (size 1.27 1.27))))
        )
      )
    )
	(symbol "antmicroCapacitors0402:C_4u7_0402" (pin_numbers hide) (pin_names hide) (in_bom yes) (on_board yes)
      (property "Reference" "C" (at 20.32 -5.08 0)
        (effects (font (size 1.27 1.27) (thickness 0.15)) (justify left bottom))
      )
      (property "Value" "C_4u7_0402" (at 20.32 -10.16 0)
        (effects (font (size 1.27 1.27) (thickness 0.15)) (justify left bottom) hide)
      )
      (property "Footprint" "antmicro-footprints:C_0402_1005Metric" (at 20.32 -12.7 0)
        (effects (font (size 1.27 1.27) (thickness 0.15)) (justify left bottom) hide)
      )
      (property "Datasheet" "https://www.murata.com/products/productdetail?partno=GRM155R61A475MEAA%23" (at 20.32 -15.24 0)
        (effects (font (size 1.27 1.27) (thickness 0.15)) (justify left bottom) hide)
      )
      (property "MPN" "GRM155R61A475MEAAD" (at 20.32 -17.78 0)
        (effects (font (size 1.27 1.27) (thickness 0.15)) (justify left bottom) hide)
      )
      (property "Manufacturer" "Murata" (at 20.32 -20.32 0)
        (effects (font (size 1.27 1.27) (thickness 0.15)) (justify left bottom) hide)
      )
      (property "License" "Apache-2.0" (at 20.32 -22.86 0)
        (effects (font (size 1.27 1.27) (thickness 0.15)) (justify left bottom) hide)
      )
      (property "Author" "Antmicro" (at 20.32 -25.4 0)
        (effects (font (size 1.27 1.27) (thickness 0.15)) (justify left bottom) hide)
      )
      (property "Val" "4u7" (at 20.32 -7.62 0)
        (effects (font (size 1.27 1.27) (thickness 0.15)) (justify left bottom))
      )
      (property "Voltage" "" (at 20.32 -27.94 0)
        (effects (font (size 1.27 1.27)) (justify left bottom) hide)
      )
      (property "Dielectric" "" (at 20.32 -30.48 0)
        (effects (font (size 1.27 1.27)) (justify left bottom) hide)
      )
      (property "ki_keywords" "0402, SMT, CAPACITOR, PASSIVE" (at 0 0 0)
        (effects (font (size 1.27 1.27)) hide)
      )
      (property "ki_description" "SMD Multilayer Ceramic Capacitor, 4.7 µF, 10 V, 0402 [1005 Metric], ± 20%, X5R, GRM Series" (at 0 0 0)
        (effects (font (size 1.27 1.27)) hide)
      )
      (symbol "C_4u7_0402_0_1"
        (polyline
          (pts
            (xy 2.032 -1.524)
            (xy 2.032 1.524)
          )
          (stroke (width 0.3048) (type default))
          (fill (type none))
        )
        (polyline
          (pts
            (xy 3.048 -1.524)
            (xy 3.048 1.524)
          )
          (stroke (width 0.3302) (type default))
          (fill (type none))
        )
      )
      (symbol "C_4u7_0402_1_1"
        (pin passive line (at 0 0 0) (length 2.032)
          (name "~" (effects (font (size 1.27 1.27))))
          (number "1" (effects (font (size 1.27 1.27))))
        )
        (pin passive line (at 5.08 0 180) (length 2.032)
          (name "~" (effects (font (size 1.27 1.27))))
          (number "2" (effects (font (size 1.27 1.27))))
        )
      )
    )
	(symbol "antmicroCapacitors0603:C_10u_25V_0603" (pin_numbers hide) (pin_names hide) (in_bom yes) (on_board yes)
      (property "Reference" "C" (at 20.32 -5.08 0)
        (effects (font (size 1.27 1.27) (thickness 0.15)) (justify left bottom))
      )
      (property "Value" "C_10u_25V_0603" (at 20.32 -10.16 0)
        (effects (font (size 1.27 1.27) (thickness 0.15)) (justify left bottom) hide)
      )
      (property "Footprint" "antmicro-footprints:C_0603_1608Metric" (at 20.32 -12.7 0)
        (effects (font (size 1.27 1.27) (thickness 0.15)) (justify left bottom) hide)
      )
      (property "Datasheet" "https://product.tdk.com/en/search/capacitor/ceramic/mlcc/info?part_no=C1608X5R1E106M080AC" (at 20.32 -15.24 0)
        (effects (font (size 1.27 1.27) (thickness 0.15)) (justify left bottom) hide)
      )
      (property "MPN" "C1608X5R1E106M080AC" (at 20.32 -17.78 0)
        (effects (font (size 1.27 1.27) (thickness 0.15)) (justify left bottom) hide)
      )
      (property "Manufacturer" "TDK" (at 20.32 -20.32 0)
        (effects (font (size 1.27 1.27) (thickness 0.15)) (justify left bottom) hide)
      )
      (property "License" "Apache-2.0" (at 20.32 -22.86 0)
        (effects (font (size 1.27 1.27) (thickness 0.15)) (justify left bottom) hide)
      )
      (property "Author" "Antmicro" (at 20.32 -25.4 0)
        (effects (font (size 1.27 1.27) (thickness 0.15)) (justify left bottom) hide)
      )
      (property "Val" "10u" (at 20.32 -7.62 0)
        (effects (font (size 1.27 1.27) (thickness 0.15)) (justify left bottom))
      )
      (property "Voltage" "25V" (at 20.32 -27.94 0)
        (effects (font (size 1.27 1.27)) (justify left bottom) hide)
      )
      (property "Dielectric" "" (at 20.32 -30.48 0)
        (effects (font (size 1.27 1.27)) (justify left bottom) hide)
      )
      (property "ki_keywords" "0603, SMT, CAPACITOR, PASSIVE, CERAMIC, MLCC" (at 0 0 0)
        (effects (font (size 1.27 1.27)) hide)
      )
      (property "ki_description" "SMD Multilayer Ceramic Capacitor, 10 µF, 25 V, 0603 [1608 Metric], ± 20%, X5R, C" (at 0 0 0)
        (effects (font (size 1.27 1.27)) hide)
      )
      (symbol "C_10u_25V_0603_0_1"
        (polyline
          (pts
            (xy 2.032 -1.524)
            (xy 2.032 1.524)
          )
          (stroke (width 0.3048) (type default))
          (fill (type none))
        )
        (polyline
          (pts
            (xy 3.048 -1.524)
            (xy 3.048 1.524)
          )
          (stroke (width 0.3302) (type default))
          (fill (type none))
        )
      )
      (symbol "C_10u_25V_0603_1_1"
        (pin passive line (at 0 0 0) (length 2.032)
          (name "~" (effects (font (size 1.27 1.27))))
          (number "1" (effects (font (size 1.27 1.27))))
        )
        (pin passive line (at 5.08 0 180) (length 2.032)
          (name "~" (effects (font (size 1.27 1.27))))
          (number "2" (effects (font (size 1.27 1.27))))
        )
      )
    )
	(symbol "antmicroCapacitors0603:C_22u_0603" (pin_numbers hide) (pin_names hide) (in_bom yes) (on_board yes)
      (property "Reference" "C" (at 20.32 -5.08 0)
        (effects (font (size 1.27 1.27) (thickness 0.15)) (justify left bottom))
      )
      (property "Value" "C_22u_0603" (at 20.32 -10.16 0)
        (effects (font (size 1.27 1.27) (thickness 0.15)) (justify left bottom) hide)
      )
      (property "Footprint" "antmicro-footprints:C_0603_1608Metric" (at 20.32 -12.7 0)
        (effects (font (size 1.27 1.27) (thickness 0.15)) (justify left bottom) hide)
      )
      (property "Datasheet" "https://www.murata.com/products/productdetail?partno=GRM188R60J226MEA0%23" (at 20.32 -15.24 0)
        (effects (font (size 1.27 1.27) (thickness 0.15)) (justify left bottom) hide)
      )
      (property "MPN" "GRM188R60J226MEA0D" (at 20.32 -17.78 0)
        (effects (font (size 1.27 1.27) (thickness 0.15)) (justify left bottom) hide)
      )
      (property "Manufacturer" "Murata" (at 20.32 -20.32 0)
        (effects (font (size 1.27 1.27) (thickness 0.15)) (justify left bottom) hide)
      )
      (property "License" "Apache-2.0" (at 20.32 -22.86 0)
        (effects (font (size 1.27 1.27) (thickness 0.15)) (justify left bottom) hide)
      )
      (property "Author" "Antmicro" (at 20.32 -25.4 0)
        (effects (font (size 1.27 1.27) (thickness 0.15)) (justify left bottom) hide)
      )
      (property "Val" "22u" (at 20.32 -7.62 0)
        (effects (font (size 1.27 1.27) (thickness 0.15)) (justify left bottom))
      )
      (property "Voltage" "" (at 20.32 -27.94 0)
        (effects (font (size 1.27 1.27)) (justify left bottom) hide)
      )
      (property "Dielectric" "" (at 20.32 -30.48 0)
        (effects (font (size 1.27 1.27)) (justify left bottom) hide)
      )
      (property "ki_keywords" "0603, SMT, CAPACITOR, PASSIVE, CERAMIC, MLCC" (at 0 0 0)
        (effects (font (size 1.27 1.27)) hide)
      )
      (property "ki_description" "SMD Multilayer Ceramic Capacitor, 22 µF, 6.3 V, 0603 [1608 Metric], ± 20%, X5R, GRM Series" (at 0 0 0)
        (effects (font (size 1.27 1.27)) hide)
      )
      (symbol "C_22u_0603_0_1"
        (polyline
          (pts
            (xy 2.032 -1.524)
            (xy 2.032 1.524)
          )
          (stroke (width 0.3048) (type default))
          (fill (type none))
        )
        (polyline
          (pts
            (xy 3.048 -1.524)
            (xy 3.048 1.524)
          )
          (stroke (width 0.3302) (type default))
          (fill (type none))
        )
      )
      (symbol "C_22u_0603_1_1"
        (pin passive line (at 0 0 0) (length 2.032)
          (name "~" (effects (font (size 1.27 1.27))))
          (number "1" (effects (font (size 1.27 1.27))))
        )
        (pin passive line (at 5.08 0 180) (length 2.032)
          (name "~" (effects (font (size 1.27 1.27))))
          (number "2" (effects (font (size 1.27 1.27))))
        )
      )
    )
	(symbol "antmicroDCDCConverters:AP62301_TSOT" (in_bom yes) (on_board yes)
      (property "Reference" "U" (at 35.56 -2.54 0)
        (effects (font (size 1.27 1.27) (thickness 0.15)) (justify left bottom))
      )
      (property "Value" "AP62301_TSOT" (at 35.56 -7.62 0)
        (effects (font (size 1.27 1.27) (thickness 0.15)) (justify left bottom) hide)
      )
      (property "Footprint" "antmicro-footprints:TSOT23-6" (at 35.56 -10.16 0)
        (effects (font (size 1.27 1.27) (thickness 0.15)) (justify left bottom) hide)
      )
      (property "Datasheet" "https://www.diodes.com/assets/Datasheets/AP62300_AP62301_AP62300T.pdf" (at 35.56 -12.7 0)
        (effects (font (size 1.27 1.27) (thickness 0.15)) (justify left bottom) hide)
      )
      (property "MPN" "AP62301WU-7" (at 35.56 -5.08 0)
        (effects (font (size 1.27 1.27) (thickness 0.15)) (justify left bottom))
      )
      (property "Manufacturer" "Diodes Incorporated" (at 35.56 -15.24 0)
        (effects (font (size 1.27 1.27) (thickness 0.15)) (justify left bottom) hide)
      )
      (property "Author" "Antmicro" (at 35.56 -17.78 0)
        (effects (font (size 1.27 1.27) (thickness 0.15)) (justify left bottom) hide)
      )
      (property "License" "Apache-2.0" (at 35.56 -20.32 0)
        (effects (font (size 1.27 1.27) (thickness 0.15)) (justify left bottom) hide)
      )
      (property "ki_keywords" "SMT, PMIC, IC, VOLTAGE" (at 0 0 0)
        (effects (font (size 1.27 1.27)) hide)
      )
      (property "ki_description" "DC-DC Switching Synchronous Buck Regulator, Adjustable, 4.2V-18Vin, 0.8V-7V/3A out, TSOT-26-6" (at 0 0 0)
        (effects (font (size 1.27 1.27)) hide)
      )
      (symbol "AP62301_TSOT_1_1"
        (rectangle (start 2.54 2.54) (end 17.78 -12.7)
          (stroke (width 0.254) (type default))
          (fill (type background))
        )
        (pin power_in line (at 0 -10.16 0) (length 2.54)
          (name "GND" (effects (font (size 1.27 1.27))))
          (number "1" (effects (font (size 1.27 1.27))))
        )
        (pin power_out line (at 20.32 0 180) (length 2.54)
          (name "SW" (effects (font (size 1.27 1.27))))
          (number "2" (effects (font (size 1.27 1.27))))
        )
        (pin power_in line (at 0 0 0) (length 2.54)
          (name "VIN" (effects (font (size 1.27 1.27))))
          (number "3" (effects (font (size 1.27 1.27))))
        )
        (pin input line (at 20.32 -10.16 180) (length 2.54)
          (name "FB" (effects (font (size 1.27 1.27))))
          (number "4" (effects (font (size 1.27 1.27))))
        )
        (pin input line (at 0 -5.08 0) (length 2.54)
          (name "EN" (effects (font (size 1.27 1.27))))
          (number "5" (effects (font (size 1.27 1.27))))
        )
        (pin output line (at 20.32 -5.08 180) (length 2.54)
          (name "BST" (effects (font (size 1.27 1.27))))
          (number "6" (effects (font (size 1.27 1.27))))
        )
      )
    )
	(symbol "antmicroDataAcquisitionAnalogtoDigitalConvertersADC:ADS7828" (in_bom yes) (on_board yes)
      (property "Reference" "U" (at 31.75 0 0)
        (effects (font (size 1.27 1.27) (thickness 0.15)) (justify left bottom))
      )
      (property "Value" "ADS7828" (at 31.75 -5.08 0)
        (effects (font (size 1.27 1.27) (thickness 0.15)) (justify left bottom) hide)
      )
      (property "Footprint" "antmicro-footprints:TSSOP-16_4.4x5mm_P0.65mm" (at 31.75 -7.62 0)
        (effects (font (size 1.27 1.27) (thickness 0.15)) (justify left bottom) hide)
      )
      (property "Datasheet" "http://www.ti.com/lit/ds/symlink/ads7828.pdf" (at 31.75 -10.16 0)
        (effects (font (size 1.27 1.27) (thickness 0.15)) (justify left bottom) hide)
      )
      (property "MPN" "ADS7828E/250" (at 31.75 -2.54 0)
        (effects (font (size 1.27 1.27) (thickness 0.15)) (justify left bottom))
      )
      (property "Manufacturer" "Texas Instruments" (at 31.75 -12.7 0)
        (effects (font (size 1.27 1.27) (thickness 0.15)) (justify left bottom) hide)
      )
      (property "Author" "Antmicro" (at 31.75 -15.24 0)
        (effects (font (size 1.27 1.27) (thickness 0.15)) (justify left bottom) hide)
      )
      (property "License" "Apache-2.0" (at 31.75 -17.78 0)
        (effects (font (size 1.27 1.27) (thickness 0.15)) (justify left bottom) hide)
      )
      (property "ki_keywords" "SMT, CONVERTER, IC, ADC, I2C" (at 0 0 0)
        (effects (font (size 1.27 1.27)) hide)
      )
      (property "ki_description" "8 channel12-bit ADC with I2C, 2V7-5V" (at 0 0 0)
        (effects (font (size 1.27 1.27)) hide)
      )
      (property "ki_fp_filters" "TSSOP*4.4x5mm*P0.65mm*" (at 0 0 0)
        (effects (font (size 1.27 1.27)) hide)
      )
      (symbol "ADS7828_1_1"
        (rectangle (start 2.54 2.54) (end 15.24 -30.48)
          (stroke (width 0.254) (type default))
          (fill (type background))
        )
        (rectangle (start 5.08 -10.16) (end 5.08 -10.16)
          (stroke (width 0.254) (type default))
          (fill (type background))
        )
        (pin input line (at 0 -5.08 0) (length 2.54)
          (name "CH0" (effects (font (size 1.27 1.27))))
          (number "1" (effects (font (size 1.27 1.27))))
        )
        (pin bidirectional line (at 17.78 -12.7 180) (length 2.54)
          (name "REF" (effects (font (size 1.27 1.27))))
          (number "10" (effects (font (size 1.27 1.27))))
        )
        (pin input line (at 0 -27.94 0) (length 2.54)
          (name "COM" (effects (font (size 1.27 1.27))))
          (number "11" (effects (font (size 1.27 1.27))))
        )
        (pin input line (at 17.78 -20.32 180) (length 2.54)
          (name "A0" (effects (font (size 1.27 1.27))))
          (number "12" (effects (font (size 1.27 1.27))))
        )
        (pin input line (at 17.78 -22.86 180) (length 2.54)
          (name "A1" (effects (font (size 1.27 1.27))))
          (number "13" (effects (font (size 1.27 1.27))))
        )
        (pin input line (at 17.78 -2.54 180) (length 2.54)
          (name "SCL" (effects (font (size 1.27 1.27))))
          (number "14" (effects (font (size 1.27 1.27))))
        )
        (pin bidirectional line (at 17.78 0 180) (length 2.54)
          (name "SDA" (effects (font (size 1.27 1.27))))
          (number "15" (effects (font (size 1.27 1.27))))
        )
        (pin power_in line (at 0 0 0) (length 2.54)
          (name "VDD" (effects (font (size 1.27 1.27))))
          (number "16" (effects (font (size 1.27 1.27))))
        )
        (pin input line (at 0 -7.62 0) (length 2.54)
          (name "CH1" (effects (font (size 1.27 1.27))))
          (number "2" (effects (font (size 1.27 1.27))))
        )
        (pin input line (at 0 -10.16 0) (length 2.54)
          (name "CH2" (effects (font (size 1.27 1.27))))
          (number "3" (effects (font (size 1.27 1.27))))
        )
        (pin input line (at 0 -12.7 0) (length 2.54)
          (name "CH3" (effects (font (size 1.27 1.27))))
          (number "4" (effects (font (size 1.27 1.27))))
        )
        (pin input line (at 0 -15.24 0) (length 2.54)
          (name "CH4" (effects (font (size 1.27 1.27))))
          (number "5" (effects (font (size 1.27 1.27))))
        )
        (pin input line (at 0 -17.78 0) (length 2.54)
          (name "CH5" (effects (font (size 1.27 1.27))))
          (number "6" (effects (font (size 1.27 1.27))))
        )
        (pin input line (at 0 -20.32 0) (length 2.54)
          (name "CH6" (effects (font (size 1.27 1.27))))
          (number "7" (effects (font (size 1.27 1.27))))
        )
        (pin input line (at 0 -22.86 0) (length 2.54)
          (name "CH7" (effects (font (size 1.27 1.27))))
          (number "8" (effects (font (size 1.27 1.27))))
        )
        (pin power_in line (at 17.78 -27.94 180) (length 2.54)
          (name "GND" (effects (font (size 1.27 1.27))))
          (number "9" (effects (font (size 1.27 1.27))))
        )
      )
    )
	(symbol "antmicroDiodesZenerSingle:BZT52B15SV-T" (pin_numbers hide) (pin_names hide) (in_bom yes) (on_board yes)
      (property "Reference" "D" (at 22.86 -5.08 0)
        (effects (font (size 1.27 1.27) (thickness 0.15)) (justify left bottom))
      )
      (property "Value" "BZT52B15SV-T" (at 22.86 -10.16 0)
        (effects (font (size 1.27 1.27) (thickness 0.15)) (justify left bottom) hide)
      )
      (property "Footprint" "antmicro-footprints:D_SOD-323" (at 22.86 -12.7 0)
        (effects (font (size 1.27 1.27) (thickness 0.15)) (justify left bottom) hide)
      )
      (property "Datasheet" "https://www.mouser.pl/datasheet/2/345/bzt52bxxsv_series-2301278.pdf" (at 22.86 -15.24 0)
        (effects (font (size 1.27 1.27) (thickness 0.15)) (justify left bottom) hide)
      )
      (property "MPN" "BZT52B15SV-T" (at 22.86 -7.62 0)
        (effects (font (size 1.27 1.27) (thickness 0.15)) (justify left bottom))
      )
      (property "Manufacturer" "Rectron" (at 22.86 -17.78 0)
        (effects (font (size 1.27 1.27) (thickness 0.15)) (justify left bottom) hide)
      )
      (property "Author" "Antmicro" (at 22.86 -20.32 0)
        (effects (font (size 1.27 1.27) (thickness 0.15)) (justify left bottom) hide)
      )
      (property "License" "Apache-2.0" (at 22.86 -22.86 0)
        (effects (font (size 1.27 1.27) (thickness 0.15)) (justify left bottom) hide)
      )
      (property "ki_keywords" "SMT, DIODE, SEMICONDUCTOR, ZENER" (at 0 0 0)
        (effects (font (size 1.27 1.27)) hide)
      )
      (property "ki_description" "Zener Single Diode, AEC-Q101, 15 V, 500 mW, SOD-323, 2 Pins, 150 °C, Surface Mount" (at 0 0 0)
        (effects (font (size 1.27 1.27)) hide)
      )
      (symbol "BZT52B15SV-T_0_1"
        (polyline
          (pts
            (xy 1.905 0)
            (xy 0.635 0)
          )
          (stroke (width 0) (type default))
          (fill (type none))
        )
        (polyline
          (pts
            (xy 4.445 0)
            (xy 3.175 0)
          )
          (stroke (width 0) (type default))
          (fill (type none))
        )
      )
      (symbol "BZT52B15SV-T_1_1"
        (polyline
          (pts
            (xy 1.778 -1.016)
            (xy 1.778 1.016)
          )
          (stroke (width 0.254) (type default))
          (fill (type none))
        )
        (polyline
          (pts
            (xy 2.159 1.016)
            (xy 1.778 1.016)
          )
          (stroke (width 0.254) (type default))
          (fill (type none))
        )
        (polyline
          (pts
            (xy 3.302 -1.016)
            (xy 3.302 1.016)
            (xy 1.778 0)
            (xy 3.302 -1.016)
          )
          (stroke (width 0.254) (type default))
          (fill (type outline))
        )
        (pin passive line (at 0 0 0) (length 0.635)
          (name "C" (effects (font (size 1.27 1.27))))
          (number "1" (effects (font (size 1.27 1.27))))
        )
        (pin passive line (at 5.08 0 180) (length 0.635)
          (name "A" (effects (font (size 1.27 1.27))))
          (number "2" (effects (font (size 1.27 1.27))))
        )
      )
    )
	(symbol "antmicroEdgeConnectors:Socket_Amphenol_HPCE_2x17_10107844-002LF" (in_bom yes) (on_board yes)
      (property "Reference" "J" (at 50.8 -2.54 0)
        (effects (font (size 1.27 1.27) (thickness 0.15)) (justify left bottom))
      )
      (property "Value" "Socket_Amphenol_HPCE_2x17_10107844-002LF" (at 50.8 -7.62 0)
        (effects (font (size 1.27 1.27) (thickness 0.15)) (justify left bottom) hide)
      )
      (property "Footprint" "antmicro-footprints:Socket_Amphenol_HPCE_2x17_10107844-002LF" (at 50.8 -10.16 0)
        (effects (font (size 1.27 1.27) (thickness 0.15)) (justify left bottom) hide)
      )
      (property "Datasheet" "https://www.farnell.com/cad/2569863.pdf" (at 50.8 -12.7 0)
        (effects (font (size 1.27 1.27) (thickness 0.15)) (justify left bottom) hide)
      )
      (property "MPN" "10107844-002LF" (at 50.8 -5.08 0)
        (effects (font (size 1.27 1.27) (thickness 0.15)) (justify left bottom))
      )
      (property "Manufacturer" "Amphenol" (at 50.8 -15.24 0)
        (effects (font (size 1.27 1.27) (thickness 0.15)) (justify left bottom) hide)
      )
      (property "Author" "Antmicro" (at 50.8 -17.78 0)
        (effects (font (size 1.27 1.27) (thickness 0.15)) (justify left bottom) hide)
      )
      (property "License" "Apache-2.0" (at 50.8 -20.32 0)
        (effects (font (size 1.27 1.27) (thickness 0.15)) (justify left bottom) hide)
      )
      (property "ki_keywords" "HORIZONTAL, EDGE, CONNECTOR, SOCKET" (at 0 0 0)
        (effects (font (size 1.27 1.27)) hide)
      )
      (property "ki_description" "60 (24 + 36 Power) Position Edge Card Connector" (at 0 0 0)
        (effects (font (size 1.27 1.27)) hide)
      )
      (symbol "Socket_Amphenol_HPCE_2x17_10107844-002LF_1_1"
        (polyline
          (pts
            (xy 7.62 -22.86)
            (xy 27.94 -22.86)
          )
          (stroke (width 0.254) (type default))
          (fill (type background))
        )
        (rectangle (start 7.62 2.54) (end 27.94 -55.88)
          (stroke (width 0.254) (type default))
          (fill (type background))
        )
        (pin power_in line (at 0 0 0) (length 7.62)
          (name "P1" (effects (font (size 1.27 1.27))))
          (number "P1/2" (effects (font (size 1.27 1.27))))
          (alternate "2" passive line)
        )
        (pin power_in line (at 0 -12.7 0) (length 7.62)
          (name "P11" (effects (font (size 1.27 1.27))))
          (number "P11/12" (effects (font (size 1.27 1.27))))
          (alternate "12" passive line)
        )
        (pin power_in line (at 0 -15.24 0) (length 7.62)
          (name "P13" (effects (font (size 1.27 1.27))))
          (number "P13/14" (effects (font (size 1.27 1.27))))
          (alternate "14" passive line)
        )
        (pin power_in line (at 0 -17.78 0) (length 7.62)
          (name "P15" (effects (font (size 1.27 1.27))))
          (number "P15/16" (effects (font (size 1.27 1.27))))
          (alternate "16" passive line)
        )
        (pin power_in line (at 0 -20.32 0) (length 7.62)
          (name "P17" (effects (font (size 1.27 1.27))))
          (number "P17/18" (effects (font (size 1.27 1.27))))
          (alternate "18" passive line)
        )
        (pin power_in line (at 35.56 -20.32 180) (length 7.62)
          (name "P19" (effects (font (size 1.27 1.27))))
          (number "P19/20" (effects (font (size 1.27 1.27))))
          (alternate "20" passive line)
        )
        (pin power_in line (at 35.56 -17.78 180) (length 7.62)
          (name "P21" (effects (font (size 1.27 1.27))))
          (number "P21/22" (effects (font (size 1.27 1.27))))
          (alternate "22" passive line)
        )
        (pin power_in line (at 35.56 -15.24 180) (length 7.62)
          (name "P23" (effects (font (size 1.27 1.27))))
          (number "P23/24" (effects (font (size 1.27 1.27))))
          (alternate "24" passive line)
        )
        (pin power_in line (at 35.56 -12.7 180) (length 7.62)
          (name "P25" (effects (font (size 1.27 1.27))))
          (number "P25/26" (effects (font (size 1.27 1.27))))
          (alternate "26" passive line)
        )
        (pin power_in line (at 35.56 -10.16 180) (length 7.62)
          (name "P27" (effects (font (size 1.27 1.27))))
          (number "P27/28" (effects (font (size 1.27 1.27))))
          (alternate "28" passive line)
        )
        (pin power_in line (at 35.56 -7.62 180) (length 7.62)
          (name "P29" (effects (font (size 1.27 1.27))))
          (number "P29/30" (effects (font (size 1.27 1.27))))
          (alternate "30" passive line)
        )
        (pin power_in line (at 0 -2.54 0) (length 7.62)
          (name "P3" (effects (font (size 1.27 1.27))))
          (number "P3/4" (effects (font (size 1.27 1.27))))
          (alternate "4" passive line)
        )
        (pin power_in line (at 35.56 -5.08 180) (length 7.62)
          (name "P31" (effects (font (size 1.27 1.27))))
          (number "P31/32" (effects (font (size 1.27 1.27))))
          (alternate "32" passive line)
        )
        (pin power_in line (at 35.56 -2.54 180) (length 7.62)
          (name "P33" (effects (font (size 1.27 1.27))))
          (number "P33/34" (effects (font (size 1.27 1.27))))
          (alternate "34" passive line)
        )
        (pin power_in line (at 35.56 0 180) (length 7.62)
          (name "P35" (effects (font (size 1.27 1.27))))
          (number "P35/36" (effects (font (size 1.27 1.27))))
          (alternate "36" passive line)
        )
        (pin power_in line (at 0 -5.08 0) (length 7.62)
          (name "P5" (effects (font (size 1.27 1.27))))
          (number "P5/6" (effects (font (size 1.27 1.27))))
          (alternate "6" passive line)
        )
        (pin power_in line (at 0 -7.62 0) (length 7.62)
          (name "P7" (effects (font (size 1.27 1.27))))
          (number "P7/8" (effects (font (size 1.27 1.27))))
          (alternate "8" passive line)
        )
        (pin power_in line (at 0 -10.16 0) (length 7.62)
          (name "P9" (effects (font (size 1.27 1.27))))
          (number "P9/10" (effects (font (size 1.27 1.27))))
          (alternate "10" passive line)
        )
        (pin passive line (at 0 -25.4 0) (length 7.62)
          (name "S1" (effects (font (size 1.27 1.27))))
          (number "S1" (effects (font (size 1.27 1.27))))
        )
        (pin passive line (at 0 -48.26 0) (length 7.62)
          (name "S10" (effects (font (size 1.27 1.27))))
          (number "S10" (effects (font (size 1.27 1.27))))
        )
        (pin passive line (at 0 -50.8 0) (length 7.62)
          (name "S11" (effects (font (size 1.27 1.27))))
          (number "S11" (effects (font (size 1.27 1.27))))
        )
        (pin passive line (at 0 -53.34 0) (length 7.62)
          (name "S12" (effects (font (size 1.27 1.27))))
          (number "S12" (effects (font (size 1.27 1.27))))
        )
        (pin passive line (at 35.56 -53.34 180) (length 7.62)
          (name "S13" (effects (font (size 1.27 1.27))))
          (number "S13" (effects (font (size 1.27 1.27))))
        )
        (pin passive line (at 35.56 -50.8 180) (length 7.62)
          (name "S14" (effects (font (size 1.27 1.27))))
          (number "S14" (effects (font (size 1.27 1.27))))
        )
        (pin passive line (at 35.56 -48.26 180) (length 7.62)
          (name "S15" (effects (font (size 1.27 1.27))))
          (number "S15" (effects (font (size 1.27 1.27))))
        )
        (pin passive line (at 35.56 -45.72 180) (length 7.62)
          (name "S16" (effects (font (size 1.27 1.27))))
          (number "S16" (effects (font (size 1.27 1.27))))
        )
        (pin passive line (at 35.56 -43.18 180) (length 7.62)
          (name "S17" (effects (font (size 1.27 1.27))))
          (number "S17" (effects (font (size 1.27 1.27))))
        )
        (pin passive line (at 35.56 -40.64 180) (length 7.62)
          (name "S18" (effects (font (size 1.27 1.27))))
          (number "S18" (effects (font (size 1.27 1.27))))
        )
        (pin passive line (at 35.56 -38.1 180) (length 7.62)
          (name "S19" (effects (font (size 1.27 1.27))))
          (number "S19" (effects (font (size 1.27 1.27))))
        )
        (pin passive line (at 0 -27.94 0) (length 7.62)
          (name "S2" (effects (font (size 1.27 1.27))))
          (number "S2" (effects (font (size 1.27 1.27))))
        )
        (pin passive line (at 35.56 -35.56 180) (length 7.62)
          (name "S20" (effects (font (size 1.27 1.27))))
          (number "S20" (effects (font (size 1.27 1.27))))
        )
        (pin passive line (at 35.56 -33.02 180) (length 7.62)
          (name "S21" (effects (font (size 1.27 1.27))))
          (number "S21" (effects (font (size 1.27 1.27))))
        )
        (pin passive line (at 35.56 -30.48 180) (length 7.62)
          (name "S22" (effects (font (size 1.27 1.27))))
          (number "S22" (effects (font (size 1.27 1.27))))
        )
        (pin passive line (at 35.56 -27.94 180) (length 7.62)
          (name "S23" (effects (font (size 1.27 1.27))))
          (number "S23" (effects (font (size 1.27 1.27))))
        )
        (pin passive line (at 35.56 -25.4 180) (length 7.62)
          (name "S24" (effects (font (size 1.27 1.27))))
          (number "S24" (effects (font (size 1.27 1.27))))
        )
        (pin passive line (at 0 -30.48 0) (length 7.62)
          (name "S3" (effects (font (size 1.27 1.27))))
          (number "S3" (effects (font (size 1.27 1.27))))
        )
        (pin passive line (at 0 -33.02 0) (length 7.62)
          (name "S4" (effects (font (size 1.27 1.27))))
          (number "S4" (effects (font (size 1.27 1.27))))
        )
        (pin passive line (at 0 -35.56 0) (length 7.62)
          (name "S5" (effects (font (size 1.27 1.27))))
          (number "S5" (effects (font (size 1.27 1.27))))
        )
        (pin passive line (at 0 -38.1 0) (length 7.62)
          (name "S6" (effects (font (size 1.27 1.27))))
          (number "S6" (effects (font (size 1.27 1.27))))
        )
        (pin passive line (at 0 -40.64 0) (length 7.62)
          (name "S7" (effects (font (size 1.27 1.27))))
          (number "S7" (effects (font (size 1.27 1.27))))
        )
        (pin passive line (at 0 -43.18 0) (length 7.62)
          (name "S8" (effects (font (size 1.27 1.27))))
          (number "S8" (effects (font (size 1.27 1.27))))
        )
        (pin passive line (at 0 -45.72 0) (length 7.62)
          (name "S9" (effects (font (size 1.27 1.27))))
          (number "S9" (effects (font (size 1.27 1.27))))
        )
      )
    )
	(symbol "antmicroFerriteBeadsandChips:FB_600Z_0.5A_Murata-BLM18AG_0603" (pin_numbers hide) (pin_names hide) (in_bom yes) (on_board yes)
      (property "Reference" "FB" (at 15.24 0 0)
        (effects (font (size 1.27 1.27) (thickness 0.15)) (justify left bottom))
      )
      (property "Value" "FB_600Z_0.5A_Murata-BLM18AG_0603" (at 15.24 -2.54 0)
        (effects (font (size 1.27 1.27) (thickness 0.15)) (justify left bottom) hide)
      )
      (property "Footprint" "antmicro-footprints:FB_0603_1608Metric" (at 15.24 -7.62 0)
        (effects (font (size 1.27 1.27) (thickness 0.15)) (justify left bottom) hide)
      )
      (property "Datasheet" "https://www.murata.com/en-us/products/productdata/8796738650142/ENFA0003.pdf" (at 15.24 -10.16 0)
        (effects (font (size 1.27 1.27) (thickness 0.15)) (justify left bottom) hide)
      )
      (property "Val" "600Z/0.5A" (at 15.24 -5.08 0)
        (effects (font (size 1.27 1.27)) (justify left bottom))
      )
      (property "MPN" "BLM18AG601SN1D" (at 15.24 -12.7 0)
        (effects (font (size 1.27 1.27) (thickness 0.15)) (justify left bottom) hide)
      )
      (property "Manufacturer" "Murata" (at 15.24 -15.24 0)
        (effects (font (size 1.27 1.27) (thickness 0.15)) (justify left bottom) hide)
      )
      (property "Current" "" (at 20.32 -22.86 0)
        (effects (font (size 1.27 1.27) (thickness 0.15)) (justify left bottom) hide)
      )
      (property "Author" "Antmicro" (at 15.24 -17.78 0)
        (effects (font (size 1.27 1.27) (thickness 0.15)) (justify left bottom) hide)
      )
      (property "License" "Apache-2.0" (at 15.24 -20.32 0)
        (effects (font (size 1.27 1.27) (thickness 0.15)) (justify left bottom) hide)
      )
      (property "ki_keywords" "0603, SMT, FERRITE BEAD, PASSIVE" (at 0 0 0)
        (effects (font (size 1.27 1.27)) hide)
      )
      (property "ki_description" "Ferrite Bead, 0603 [1608 Metric], 600 ohm, 500 mA, BLM18A, 0.38 ohm, ± 25%, General use" (at 0 0 0)
        (effects (font (size 1.27 1.27)) hide)
      )
      (symbol "FB_600Z_0.5A_Murata-BLM18AG_0603_0_1"
        (polyline
          (pts
            (xy 1.651 0)
            (xy 1.2446 0)
          )
          (stroke (width 0) (type default))
          (fill (type none))
        )
        (polyline
          (pts
            (xy 3.81 0)
            (xy 3.3274 0)
          )
          (stroke (width 0) (type default))
          (fill (type none))
        )
        (polyline
          (pts
            (xy 2.2606 -1.8288)
            (xy 1.0414 -1.1176)
            (xy 2.7432 1.8288)
            (xy 3.9624 1.1176)
            (xy 2.2606 -1.8288)
          )
          (stroke (width 0) (type default))
          (fill (type none))
        )
      )
      (symbol "FB_600Z_0.5A_Murata-BLM18AG_0603_1_1"
        (pin passive line (at 0 0 0) (length 1.27)
          (name "~" (effects (font (size 1.27 1.27))))
          (number "1" (effects (font (size 1.27 1.27))))
        )
        (pin passive line (at 5.08 0 180) (length 1.27)
          (name "~" (effects (font (size 1.27 1.27))))
          (number "2" (effects (font (size 1.27 1.27))))
        )
      )
    )
	(symbol "antmicroFixedInductors:L_3u3_4.1A_WE-LHMI-5030" (pin_numbers hide) (pin_names hide) (in_bom yes) (on_board yes)
      (property "Reference" "L" (at 13.97 0 0)
        (effects (font (size 1.27 1.27) (thickness 0.15)) (justify left bottom))
      )
      (property "Value" "L_3u3_4.1A_WE-LHMI-5030" (at 13.97 -2.54 0)
        (effects (font (size 1.27 1.27) (thickness 0.15)) (justify left bottom) hide)
      )
      (property "Footprint" "antmicro-footprints:L_WE-LHMI-5030" (at 13.97 -7.62 0)
        (effects (font (size 1.27 1.27) (thickness 0.15)) (justify left bottom) hide)
      )
      (property "Datasheet" "https://www.we-online.com/catalog/datasheet/74437336033.pdf" (at 13.97 -10.16 0)
        (effects (font (size 1.27 1.27) (thickness 0.15)) (justify left bottom) hide)
      )
      (property "Val" "3u3/4.1A" (at 13.97 -5.08 0)
        (effects (font (size 1.27 1.27) (thickness 0.15)) (justify left bottom))
      )
      (property "Manufacturer" "Würth Elektronik" (at 13.97 -12.7 0)
        (effects (font (size 1.27 1.27) (thickness 0.15)) (justify left bottom) hide)
      )
      (property "MPN" "74437336033" (at 13.97 -15.24 0)
        (effects (font (size 1.27 1.27) (thickness 0.15)) (justify left bottom) hide)
      )
      (property "ISat" "5.45A" (at 13.97 -16.51 0)
        (effects (font (size 1.27 1.27)) (justify left) hide)
      )
      (property "IMax" "4.1A" (at 13.97 -20.32 0)
        (effects (font (size 1.27 1.27) (thickness 0.15)) (justify left bottom) hide)
      )
      (property "Size" "5.2x5.2" (at 13.97 -22.86 0)
        (effects (font (size 1.27 1.27) (thickness 0.15)) (justify left bottom) hide)
      )
      (property "Author" "Antmicro" (at 13.97 -25.4 0)
        (effects (font (size 1.27 1.27) (thickness 0.15)) (justify left bottom) hide)
      )
      (property "License" "Apache-2.0" (at 13.97 -27.94 0)
        (effects (font (size 1.27 1.27) (thickness 0.15)) (justify left bottom) hide)
      )
      (property "ki_keywords" "SMT, INDUCTOR, PASSIVE" (at 0 0 0)
        (effects (font (size 1.27 1.27)) hide)
      )
      (property "ki_description" "Power Inductor (SMT), 3.3 µH, 4.1 A, Shielded, 8.4 A, WE-LHMI" (at 0 0 0)
        (effects (font (size 1.27 1.27)) hide)
      )
      (symbol "L_3u3_4.1A_WE-LHMI-5030_0_1"
        (arc (start 1.524 0) (mid 1.016 0.5058) (end 0.508 0)
          (stroke (width 0) (type default))
          (fill (type none))
        )
        (arc (start 2.54 0) (mid 2.032 0.5058) (end 1.524 0)
          (stroke (width 0) (type default))
          (fill (type none))
        )
        (arc (start 3.556 0) (mid 3.048 0.5058) (end 2.54 0)
          (stroke (width 0) (type default))
          (fill (type none))
        )
        (arc (start 4.572 0) (mid 4.064 0.5058) (end 3.556 0)
          (stroke (width 0) (type default))
          (fill (type none))
        )
      )
      (symbol "L_3u3_4.1A_WE-LHMI-5030_1_1"
        (pin passive line (at 0 0 0) (length 0.508)
          (name "~" (effects (font (size 1.27 1.27))))
          (number "1" (effects (font (size 1.27 1.27))))
        )
        (pin passive line (at 5.08 0 180) (length 0.508)
          (name "~" (effects (font (size 1.27 1.27))))
          (number "2" (effects (font (size 1.27 1.27))))
        )
      )
    )
	(symbol "antmicroGenericPinHeaders:PinHeader_1x3_P2.54mm_Drill1.1mm" (in_bom yes) (on_board yes)
      (property "Reference" "J" (at 20.32 -5.08 0)
        (effects (font (size 1.27 1.27) (thickness 0.15)) (justify left bottom))
      )
      (property "Value" "PinHeader_1x3_P2.54mm_Drill1.1mm" (at 20.32 -10.16 0)
        (effects (font (size 1.27 1.27) (thickness 0.15)) (justify left bottom) hide)
      )
      (property "Footprint" "antmicro-footprints:PinHeader_1x3_P2.54mm_Drill1.1mm" (at 20.32 -12.7 0)
        (effects (font (size 1.27 1.27) (thickness 0.15)) (justify left bottom) hide)
      )
      (property "Datasheet" "https://katalog.we-online.de/em/datasheet/6130xx11121.pdf" (at 20.32 -15.24 0)
        (effects (font (size 1.27 1.27) (thickness 0.15)) (justify left bottom) hide)
      )
      (property "MPN" "61300311121" (at 20.32 -7.62 0)
        (effects (font (size 1.27 1.27) (thickness 0.15)) (justify left bottom))
      )
      (property "Manufacturer" "Würth Elektronik" (at 20.32 -17.78 0)
        (effects (font (size 1.27 1.27) (thickness 0.15)) (justify left bottom) hide)
      )
      (property "Author" "Antmicro" (at 20.32 -20.32 0)
        (effects (font (size 1.27 1.27) (thickness 0.15)) (justify left bottom) hide)
      )
      (property "License" "Apache-2.0" (at 20.32 -22.86 0)
        (effects (font (size 1.27 1.27) (thickness 0.15)) (justify left bottom) hide)
      )
      (property "ki_keywords" "VERTICAL, THT, HEADER, CONNECTOR, MALE" (at 0 0 0)
        (effects (font (size 1.27 1.27)) hide)
      )
      (property "ki_description" "Pin Header, Vertical, Board-to-Board, 2.54 mm, 1 Rows, 3 Contacts, Through Hole Straight, WR-PHD" (at 0 0 0)
        (effects (font (size 1.27 1.27)) hide)
      )
      (symbol "PinHeader_1x3_P2.54mm_Drill1.1mm_1_1"
        (rectangle (start 2.54 2.54) (end 5.08 -7.62)
          (stroke (width 0.254) (type default))
          (fill (type background))
        )
        (rectangle (start 4.191 -5.334) (end 3.683 -4.826)
          (stroke (width 0.254) (type default))
          (fill (type none))
        )
        (rectangle (start 4.191 -2.794) (end 3.683 -2.286)
          (stroke (width 0.254) (type default))
          (fill (type none))
        )
        (rectangle (start 4.191 -0.254) (end 3.683 0.254)
          (stroke (width 0.254) (type default))
          (fill (type none))
        )
        (pin passive line (at 0 0 0) (length 2.54)
          (name "~" (effects (font (size 1.27 1.27))))
          (number "1" (effects (font (size 1.27 1.27))))
        )
        (pin passive line (at 0 -2.54 0) (length 2.54)
          (name "~" (effects (font (size 1.27 1.27))))
          (number "2" (effects (font (size 1.27 1.27))))
        )
        (pin passive line (at 0 -5.08 0) (length 2.54)
          (name "~" (effects (font (size 1.27 1.27))))
          (number "3" (effects (font (size 1.27 1.27))))
        )
      )
    )
	(symbol "antmicroInterfaceControllers:FT4232H_VQFN" (in_bom yes) (on_board yes)
      (property "Reference" "U" (at 55.88 -2.54 0)
        (effects (font (size 1.27 1.27) (thickness 0.15)) (justify left bottom))
      )
      (property "Value" "FT4232H_VQFN" (at 55.88 -15.24 0)
        (effects (font (size 1.27 1.27) (thickness 0.15)) (justify left bottom) hide)
      )
      (property "Footprint" "antmicro-footprints:QFN-56-1EP_8x8mm_P0.5mm" (at 55.88 -7.62 0)
        (effects (font (size 1.27 1.27) (thickness 0.15)) (justify left bottom) hide)
      )
      (property "Datasheet" "https://www.ftdichip.com/Support/Documents/DataSheets/ICs/DS_FT4232H.pdf" (at 55.88 -10.16 0)
        (effects (font (size 1.27 1.27) (thickness 0.15)) (justify left bottom) hide)
      )
      (property "Manufacturer" "FTDI Chip" (at 55.88 -12.7 0)
        (effects (font (size 1.27 1.27) (thickness 0.15)) (justify left bottom) hide)
      )
      (property "MPN" "FT4232H-56Q-REEL" (at 55.88 -5.08 0)
        (effects (font (size 1.27 1.27) (thickness 0.15)) (justify left bottom))
      )
      (property "Author" "Antmicro" (at 55.88 -17.78 0)
        (effects (font (size 1.27 1.27) (thickness 0.15)) (justify left bottom) hide)
      )
      (property "License" "Apache-2.0" (at 55.88 -20.32 0)
        (effects (font (size 1.27 1.27) (thickness 0.15)) (justify left bottom) hide)
      )
      (property "ki_keywords" "SMT, INTERFACE, IC, CONTROLLER, USB, UART, I2C, SPI, JTAG" (at 0 0 0)
        (effects (font (size 1.27 1.27)) hide)
      )
      (property "ki_description" "Interface Bridges, USB to UART, MPSSE, 1.62 V, 1.98 V, VQFN, 56 Pins, -40 °C" (at 0 0 0)
        (effects (font (size 1.27 1.27)) hide)
      )
      (symbol "FT4232H_VQFN_1_1"
        (rectangle (start 2.54 2.54) (end 38.1 -93.98)
          (stroke (width 0.254) (type default))
          (fill (type background))
        )
        (pin bidirectional line (at 0 -44.45 0) (length 2.54)
          (name "EECS" (effects (font (size 1.27 1.27))))
          (number "1" (effects (font (size 1.27 1.27))))
        )
        (pin input line (at 0 -88.9 0) (length 2.54)
          (name "TEST" (effects (font (size 1.27 1.27))))
          (number "10" (effects (font (size 1.27 1.27))))
        )
        (pin input line (at 0 -36.83 0) (length 2.54)
          (name "~{RESET}" (effects (font (size 1.27 1.27))))
          (number "11" (effects (font (size 1.27 1.27))))
        )
        (pin bidirectional line (at 40.64 0 180) (length 2.54)
          (name "ADBUS0" (effects (font (size 1.27 1.27))))
          (number "12" (effects (font (size 1.27 1.27))))
        )
        (pin bidirectional line (at 40.64 -2.54 180) (length 2.54)
          (name "ADBUS1" (effects (font (size 1.27 1.27))))
          (number "13" (effects (font (size 1.27 1.27))))
        )
        (pin bidirectional line (at 40.64 -5.08 180) (length 2.54)
          (name "ADBUS2" (effects (font (size 1.27 1.27))))
          (number "14" (effects (font (size 1.27 1.27))))
        )
        (pin bidirectional line (at 40.64 -7.62 180) (length 2.54)
          (name "ADBUS3" (effects (font (size 1.27 1.27))))
          (number "15" (effects (font (size 1.27 1.27))))
        )
        (pin power_in line (at 0 -2.54 0) (length 2.54)
          (name "V_{CCIO}" (effects (font (size 1.27 1.27))))
          (number "16" (effects (font (size 1.27 1.27))))
        )
        (pin bidirectional line (at 40.64 -10.16 180) (length 2.54)
          (name "ADBUS4" (effects (font (size 1.27 1.27))))
          (number "17" (effects (font (size 1.27 1.27))))
        )
        (pin bidirectional line (at 40.64 -12.7 180) (length 2.54)
          (name "ADBUS5" (effects (font (size 1.27 1.27))))
          (number "18" (effects (font (size 1.27 1.27))))
        )
        (pin bidirectional line (at 40.64 -15.24 180) (length 2.54)
          (name "ADBUS6" (effects (font (size 1.27 1.27))))
          (number "19" (effects (font (size 1.27 1.27))))
        )
        (pin power_in line (at 0 -15.24 0) (length 2.54)
          (name "V_{CORE}" (effects (font (size 1.27 1.27))))
          (number "2" (effects (font (size 1.27 1.27))))
        )
        (pin bidirectional line (at 40.64 -17.78 180) (length 2.54)
          (name "ADBUS7" (effects (font (size 1.27 1.27))))
          (number "20" (effects (font (size 1.27 1.27))))
        )
        (pin power_in line (at 0 -91.44 0) (length 2.54)
          (name "GND" (effects (font (size 1.27 1.27))))
          (number "21" (effects (font (size 1.27 1.27))))
        )
        (pin bidirectional line (at 40.64 -21.59 180) (length 2.54)
          (name "BDBUS0" (effects (font (size 1.27 1.27))))
          (number "22" (effects (font (size 1.27 1.27))))
        )
        (pin bidirectional line (at 40.64 -24.13 180) (length 2.54)
          (name "BDBUS1" (effects (font (size 1.27 1.27))))
          (number "23" (effects (font (size 1.27 1.27))))
        )
        (pin bidirectional line (at 40.64 -26.67 180) (length 2.54)
          (name "BDBUS2" (effects (font (size 1.27 1.27))))
          (number "24" (effects (font (size 1.27 1.27))))
        )
        (pin bidirectional line (at 40.64 -29.21 180) (length 2.54)
          (name "BDBUS3" (effects (font (size 1.27 1.27))))
          (number "25" (effects (font (size 1.27 1.27))))
        )
        (pin bidirectional line (at 40.64 -31.75 180) (length 2.54)
          (name "BDBUS4" (effects (font (size 1.27 1.27))))
          (number "26" (effects (font (size 1.27 1.27))))
        )
        (pin bidirectional line (at 40.64 -34.29 180) (length 2.54)
          (name "BDBUS5" (effects (font (size 1.27 1.27))))
          (number "27" (effects (font (size 1.27 1.27))))
        )
        (pin bidirectional line (at 40.64 -36.83 180) (length 2.54)
          (name "BDBUS6" (effects (font (size 1.27 1.27))))
          (number "28" (effects (font (size 1.27 1.27))))
        )
        (pin bidirectional line (at 40.64 -39.37 180) (length 2.54)
          (name "BDBUS7" (effects (font (size 1.27 1.27))))
          (number "29" (effects (font (size 1.27 1.27))))
        )
        (pin input line (at 0 -54.61 0) (length 2.54)
          (name "OSCI" (effects (font (size 1.27 1.27))))
          (number "3" (effects (font (size 1.27 1.27))))
        )
        (pin output line (at 40.64 -90.17 180) (length 2.54)
          (name "~{SUSPEND}" (effects (font (size 1.27 1.27))))
          (number "30" (effects (font (size 1.27 1.27))))
        )
        (pin passive line (at 0 -15.24 0) (length 2.54) hide
          (name "V_{CORE}" (effects (font (size 1.27 1.27))))
          (number "31" (effects (font (size 1.27 1.27))))
        )
        (pin bidirectional line (at 40.64 -43.18 180) (length 2.54)
          (name "CDBUS0" (effects (font (size 1.27 1.27))))
          (number "32" (effects (font (size 1.27 1.27))))
        )
        (pin bidirectional line (at 40.64 -45.72 180) (length 2.54)
          (name "CDBUS1" (effects (font (size 1.27 1.27))))
          (number "33" (effects (font (size 1.27 1.27))))
        )
        (pin bidirectional line (at 40.64 -48.26 180) (length 2.54)
          (name "CDBUS2" (effects (font (size 1.27 1.27))))
          (number "34" (effects (font (size 1.27 1.27))))
        )
        (pin bidirectional line (at 40.64 -50.8 180) (length 2.54)
          (name "CDBUS3" (effects (font (size 1.27 1.27))))
          (number "35" (effects (font (size 1.27 1.27))))
        )
        (pin passive line (at 0 -2.54 0) (length 2.54) hide
          (name "V_{CCIO}" (effects (font (size 1.27 1.27))))
          (number "36" (effects (font (size 1.27 1.27))))
        )
        (pin bidirectional line (at 40.64 -53.34 180) (length 2.54)
          (name "CDBUS4" (effects (font (size 1.27 1.27))))
          (number "37" (effects (font (size 1.27 1.27))))
        )
        (pin bidirectional line (at 40.64 -55.88 180) (length 2.54)
          (name "CDBUS5" (effects (font (size 1.27 1.27))))
          (number "38" (effects (font (size 1.27 1.27))))
        )
        (pin bidirectional line (at 40.64 -58.42 180) (length 2.54)
          (name "CDBUS6" (effects (font (size 1.27 1.27))))
          (number "39" (effects (font (size 1.27 1.27))))
        )
        (pin output line (at 0 -59.69 0) (length 2.54)
          (name "OSCO" (effects (font (size 1.27 1.27))))
          (number "4" (effects (font (size 1.27 1.27))))
        )
        (pin bidirectional line (at 40.64 -60.96 180) (length 2.54)
          (name "CDBUS7" (effects (font (size 1.27 1.27))))
          (number "40" (effects (font (size 1.27 1.27))))
        )
        (pin passive line (at 0 -91.44 0) (length 2.54) hide
          (name "GND" (effects (font (size 1.27 1.27))))
          (number "41" (effects (font (size 1.27 1.27))))
        )
        (pin bidirectional line (at 40.64 -64.77 180) (length 2.54)
          (name "DDBUS0" (effects (font (size 1.27 1.27))))
          (number "42" (effects (font (size 1.27 1.27))))
        )
        (pin power_out line (at 0 -6.35 0) (length 2.54)
          (name "V_{REGOUT}" (effects (font (size 1.27 1.27))))
          (number "43" (effects (font (size 1.27 1.27))))
        )
        (pin power_in line (at 0 0 0) (length 2.54)
          (name "V_{REGIN}" (effects (font (size 1.27 1.27))))
          (number "44" (effects (font (size 1.27 1.27))))
        )
        (pin passive line (at 0 -91.44 0) (length 2.54) hide
          (name "GND" (effects (font (size 1.27 1.27))))
          (number "45" (effects (font (size 1.27 1.27))))
        )
        (pin bidirectional line (at 40.64 -67.31 180) (length 2.54)
          (name "DDBUS1" (effects (font (size 1.27 1.27))))
          (number "46" (effects (font (size 1.27 1.27))))
        )
        (pin bidirectional line (at 40.64 -69.85 180) (length 2.54)
          (name "DDBUS2" (effects (font (size 1.27 1.27))))
          (number "47" (effects (font (size 1.27 1.27))))
        )
        (pin bidirectional line (at 40.64 -72.39 180) (length 2.54)
          (name "DDBUS3" (effects (font (size 1.27 1.27))))
          (number "48" (effects (font (size 1.27 1.27))))
        )
        (pin bidirectional line (at 40.64 -74.93 180) (length 2.54)
          (name "DDBUS4" (effects (font (size 1.27 1.27))))
          (number "49" (effects (font (size 1.27 1.27))))
        )
        (pin power_in line (at 0 -10.16 0) (length 2.54)
          (name "V_{PHY}" (effects (font (size 1.27 1.27))))
          (number "5" (effects (font (size 1.27 1.27))))
        )
        (pin passive line (at 0 -2.54 0) (length 2.54) hide
          (name "V_{CCIO}" (effects (font (size 1.27 1.27))))
          (number "50" (effects (font (size 1.27 1.27))))
        )
        (pin bidirectional line (at 40.64 -77.47 180) (length 2.54)
          (name "DDBUS5" (effects (font (size 1.27 1.27))))
          (number "51" (effects (font (size 1.27 1.27))))
        )
        (pin bidirectional line (at 40.64 -80.01 180) (length 2.54)
          (name "DDBUS6" (effects (font (size 1.27 1.27))))
          (number "52" (effects (font (size 1.27 1.27))))
        )
        (pin bidirectional line (at 40.64 -82.55 180) (length 2.54)
          (name "DDBUS7" (effects (font (size 1.27 1.27))))
          (number "53" (effects (font (size 1.27 1.27))))
        )
        (pin output line (at 40.64 -87.63 180) (length 2.54)
          (name "~{PWR_{EN}}" (effects (font (size 1.27 1.27))))
          (number "54" (effects (font (size 1.27 1.27))))
        )
        (pin bidirectional line (at 0 -49.53 0) (length 2.54)
          (name "EEDATA" (effects (font (size 1.27 1.27))))
          (number "55" (effects (font (size 1.27 1.27))))
        )
        (pin output line (at 0 -46.99 0) (length 2.54)
          (name "EECLK" (effects (font (size 1.27 1.27))))
          (number "56" (effects (font (size 1.27 1.27))))
        )
        (pin passive line (at 0 -91.44 0) (length 2.54) hide
          (name "GND" (effects (font (size 1.27 1.27))))
          (number "57" (effects (font (size 1.27 1.27))))
        )
        (pin input line (at 0 -77.47 0) (length 2.54)
          (name "REF" (effects (font (size 1.27 1.27))))
          (number "6" (effects (font (size 1.27 1.27))))
        )
        (pin bidirectional line (at 0 -25.4 0) (length 2.54)
          (name "D-" (effects (font (size 1.27 1.27))))
          (number "7" (effects (font (size 1.27 1.27))))
        )
        (pin bidirectional line (at 0 -22.86 0) (length 2.54)
          (name "D+" (effects (font (size 1.27 1.27))))
          (number "8" (effects (font (size 1.27 1.27))))
        )
        (pin power_in line (at 0 -12.7 0) (length 2.54)
          (name "V_{PLL}" (effects (font (size 1.27 1.27))))
          (number "9" (effects (font (size 1.27 1.27))))
        )
      )
    )
	(symbol "antmicroInterfaceIOExpanders:TCA9534PWR_TSSOP" (in_bom yes) (on_board yes)
      (property "Reference" "U" (at 33.02 -2.54 0)
        (effects (font (size 1.27 1.27) (thickness 0.15)) (justify left bottom))
      )
      (property "Value" "TCA9534PWR_TSSOP" (at 33.02 -7.62 0)
        (effects (font (size 1.27 1.27) (thickness 0.15)) (justify left bottom) hide)
      )
      (property "Footprint" "antmicro-footprints:TSSOP-16_4.4x5mm_P0.65mm" (at 33.02 -10.16 0)
        (effects (font (size 1.27 1.27) (thickness 0.15)) (justify left bottom) hide)
      )
      (property "Datasheet" "http://www.ti.com/lit/ds/symlink/tca9534.pdf" (at 33.02 -12.7 0)
        (effects (font (size 1.27 1.27) (thickness 0.15)) (justify left bottom) hide)
      )
      (property "MPN" "TCA9534PWR" (at 33.02 -5.08 0)
        (effects (font (size 1.27 1.27) (thickness 0.15)) (justify left bottom))
      )
      (property "Manufacturer" "Texas Instruments" (at 33.02 -15.24 0)
        (effects (font (size 1.27 1.27) (thickness 0.15)) (justify left bottom) hide)
      )
      (property "Author" "Antmicro" (at 33.02 -17.78 0)
        (effects (font (size 1.27 1.27) (thickness 0.15)) (justify left bottom) hide)
      )
      (property "License" "Apache-2.0" (at 33.02 -20.32 0)
        (effects (font (size 1.27 1.27) (thickness 0.15)) (justify left bottom) hide)
      )
      (property "ki_keywords" "SMT, INTERFACE, IC, I2C" (at 0 0 0)
        (effects (font (size 1.27 1.27)) hide)
      )
      (property "ki_description" "Low Voltage 8-Bit I2C and SMBUS Low-Power I/O Expander with Interrupt Output and Configuration Registers" (at 0 0 0)
        (effects (font (size 1.27 1.27)) hide)
      )
      (property "ki_fp_filters" "TSSOP*4.4x5mm*P0.65mm* SOIC*7.5x10.3mm*P1.27mm*" (at 0 0 0)
        (effects (font (size 1.27 1.27)) hide)
      )
      (symbol "TCA9534PWR_TSSOP_1_1"
        (rectangle (start 2.54 -22.86) (end 15.24 2.54)
          (stroke (width 0.254) (type default))
          (fill (type background))
        )
        (pin input line (at 0 -12.7 0) (length 2.54)
          (name "A0" (effects (font (size 1.27 1.27))))
          (number "1" (effects (font (size 1.27 1.27))))
        )
        (pin bidirectional line (at 17.78 -12.7 180) (length 2.54)
          (name "P5" (effects (font (size 1.27 1.27))))
          (number "10" (effects (font (size 1.27 1.27))))
        )
        (pin bidirectional line (at 17.78 -15.24 180) (length 2.54)
          (name "P6" (effects (font (size 1.27 1.27))))
          (number "11" (effects (font (size 1.27 1.27))))
        )
        (pin bidirectional line (at 17.78 -17.78 180) (length 2.54)
          (name "P7" (effects (font (size 1.27 1.27))))
          (number "12" (effects (font (size 1.27 1.27))))
        )
        (pin open_collector line (at 0 -8.89 0) (length 2.54)
          (name "~{INT}" (effects (font (size 1.27 1.27))))
          (number "13" (effects (font (size 1.27 1.27))))
        )
        (pin input line (at 0 -6.35 0) (length 2.54)
          (name "SCL" (effects (font (size 1.27 1.27))))
          (number "14" (effects (font (size 1.27 1.27))))
        )
        (pin bidirectional line (at 0 -3.81 0) (length 2.54)
          (name "SDA" (effects (font (size 1.27 1.27))))
          (number "15" (effects (font (size 1.27 1.27))))
        )
        (pin power_in line (at 0 0 0) (length 2.54)
          (name "VCC" (effects (font (size 1.27 1.27))))
          (number "16" (effects (font (size 1.27 1.27))))
        )
        (pin input line (at 0 -15.24 0) (length 2.54)
          (name "A1" (effects (font (size 1.27 1.27))))
          (number "2" (effects (font (size 1.27 1.27))))
        )
        (pin input line (at 0 -17.78 0) (length 2.54)
          (name "A2" (effects (font (size 1.27 1.27))))
          (number "3" (effects (font (size 1.27 1.27))))
        )
        (pin bidirectional line (at 17.78 0 180) (length 2.54)
          (name "P0" (effects (font (size 1.27 1.27))))
          (number "4" (effects (font (size 1.27 1.27))))
        )
        (pin bidirectional line (at 17.78 -2.54 180) (length 2.54)
          (name "P1" (effects (font (size 1.27 1.27))))
          (number "5" (effects (font (size 1.27 1.27))))
        )
        (pin bidirectional line (at 17.78 -5.08 180) (length 2.54)
          (name "P2" (effects (font (size 1.27 1.27))))
          (number "6" (effects (font (size 1.27 1.27))))
        )
        (pin bidirectional line (at 17.78 -7.62 180) (length 2.54)
          (name "P3" (effects (font (size 1.27 1.27))))
          (number "7" (effects (font (size 1.27 1.27))))
        )
        (pin power_in line (at 0 -20.32 0) (length 2.54)
          (name "GND" (effects (font (size 1.27 1.27))))
          (number "8" (effects (font (size 1.27 1.27))))
        )
        (pin bidirectional line (at 17.78 -10.16 180) (length 2.54)
          (name "P4" (effects (font (size 1.27 1.27))))
          (number "9" (effects (font (size 1.27 1.27))))
        )
      )
    )
	(symbol "antmicroLEDIndicationDiscrete:LED_G_0603_LG_L29K-G2J1-24-Z" (pin_numbers hide) (pin_names hide) (in_bom yes) (on_board yes)
      (property "Reference" "D" (at 20.32 -2.54 0)
        (effects (font (size 1.27 1.27) (thickness 0.15)) (justify left bottom))
      )
      (property "Value" "LED_G_0603_LG_L29K-G2J1-24-Z" (at 20.32 -7.62 0)
        (effects (font (size 1.27 1.27) (thickness 0.15)) (justify left bottom) hide)
      )
      (property "Footprint" "antmicro-footprints:LED_0603_1608Metric_G" (at 20.32 -10.16 0)
        (effects (font (size 1.27 1.27) (thickness 0.15)) (justify left bottom) hide)
      )
      (property "Datasheet" "https://look.ams-osram.com/m/19ee86b3ae0ee95b/original/LG-L29K.pdf" (at 20.32 -12.7 0)
        (effects (font (size 1.27 1.27) (thickness 0.15)) (justify left bottom) hide)
      )
      (property "MPN" "LG L29K-G2J1-24-Z" (at 20.32 -15.24 0)
        (effects (font (size 1.27 1.27) (thickness 0.15)) (justify left bottom) hide)
      )
      (property "Manufacturer" "OSRAM" (at 20.32 -17.78 0)
        (effects (font (size 1.27 1.27) (thickness 0.15)) (justify left bottom) hide)
      )
      (property "Color" "Green" (at 20.32 -5.08 0)
        (effects (font (size 1.27 1.27)) (justify left bottom))
      )
      (property "Author" "Antmicro" (at 20.32 -20.32 0)
        (effects (font (size 1.27 1.27) (thickness 0.15)) (justify left bottom) hide)
      )
      (property "License" "Apache-2.0" (at 20.32 -22.86 0)
        (effects (font (size 1.27 1.27) (thickness 0.15)) (justify left bottom) hide)
      )
      (property "ki_keywords" "SMT, DIODE, SEMICONDUCTOR, LED" (at 0 0 0)
        (effects (font (size 1.27 1.27)) hide)
      )
      (property "ki_description" "LED, Green, SMD, 0603, 20 mA, 1.7 V, 570 nm" (at 0 0 0)
        (effects (font (size 1.27 1.27)) hide)
      )
      (symbol "LED_G_0603_LG_L29K-G2J1-24-Z_0_1"
        (polyline
          (pts
            (xy 1.905 0)
            (xy 0.635 0)
          )
          (stroke (width 0) (type default))
          (fill (type none))
        )
        (polyline
          (pts
            (xy 4.445 0)
            (xy 3.175 0)
          )
          (stroke (width 0) (type default))
          (fill (type none))
        )
      )
      (symbol "LED_G_0603_LG_L29K-G2J1-24-Z_1_1"
        (polyline
          (pts
            (xy 1.778 1.016)
            (xy 1.778 -1.016)
          )
          (stroke (width 0.254) (type default))
          (fill (type none))
        )
        (polyline
          (pts
            (xy 3.302 1.016)
            (xy 3.302 -1.016)
            (xy 1.778 0)
            (xy 3.302 1.016)
          )
          (stroke (width 0.254) (type default))
          (fill (type outline))
        )
        (polyline
          (pts
            (xy 1.143 2.286)
            (xy 1.143 1.778)
            (xy 1.143 2.286)
            (xy 1.651 2.286)
            (xy 1.143 2.286)
            (xy 2.159 1.27)
          )
          (stroke (width 0.254) (type default))
          (fill (type none))
        )
        (polyline
          (pts
            (xy 2.159 2.54)
            (xy 2.159 2.032)
            (xy 2.159 2.54)
            (xy 2.667 2.54)
            (xy 2.159 2.54)
            (xy 3.048 1.651)
          )
          (stroke (width 0.254) (type default))
          (fill (type none))
        )
        (pin passive line (at 0 0 0) (length 0.635)
          (name "C" (effects (font (size 1.27 1.27))))
          (number "1" (effects (font (size 1.27 1.27))))
        )
        (pin passive line (at 5.08 0 180) (length 0.635)
          (name "A" (effects (font (size 1.27 1.27))))
          (number "2" (effects (font (size 1.27 1.27))))
        )
      )
    )
	(symbol "antmicroLogicBuffersDriversReceiversTransceivers:SN74AUP1G17_SC70" (in_bom yes) (on_board yes)
      (property "Reference" "U" (at 33.02 -2.54 0)
        (effects (font (size 1.27 1.27) (thickness 0.15)) (justify left bottom))
      )
      (property "Value" "SN74AUP1G17_SC70" (at 33.02 -5.08 0)
        (effects (font (size 1.27 1.27) (thickness 0.15)) (justify left bottom) hide)
      )
      (property "Footprint" "antmicro-footprints:SC-70-5" (at 33.02 -7.62 0)
        (effects (font (size 1.27 1.27) (thickness 0.15)) (justify left bottom) hide)
      )
      (property "Datasheet" "https://www.ti.com/lit/ds/symlink/sn74aup1g17.pdf" (at 33.02 -10.16 0)
        (effects (font (size 1.27 1.27) (thickness 0.15)) (justify left bottom) hide)
      )
      (property "MPN" "SN74AUP1G17DCKR" (at 33.02 -12.7 0)
        (effects (font (size 1.27 1.27) (thickness 0.15)) (justify left bottom))
      )
      (property "Manufacturer" "Texas Instruments" (at 33.02 -15.24 0)
        (effects (font (size 1.27 1.27) (thickness 0.15)) (justify left bottom) hide)
      )
      (property "Author" "Antmicro" (at 33.02 -17.78 0)
        (effects (font (size 1.27 1.27) (thickness 0.15)) (justify left bottom) hide)
      )
      (property "License" "Apache-2.0" (at 33.02 -20.32 0)
        (effects (font (size 1.27 1.27) (thickness 0.15)) (justify left bottom) hide)
      )
      (property "ki_keywords" "SMT, LOGIC, IC, BUFFER, TRANSCEIVER" (at 0 0 0)
        (effects (font (size 1.27 1.27)) hide)
      )
      (property "ki_description" "Buffer, 74AUP1G17, 0.8 V to 3.6 V, TSSOP-5" (at 0 0 0)
        (effects (font (size 1.27 1.27)) hide)
      )
      (symbol "SN74AUP1G17_SC70_1_1"
        (polyline
          (pts
            (xy 6.35 -3.81)
            (xy 5.08 -3.81)
          )
          (stroke (width 0.254) (type default))
          (fill (type background))
        )
        (polyline
          (pts
            (xy 7.874 -3.175)
            (xy 7.874 -4.445)
          )
          (stroke (width 0.254) (type default))
          (fill (type background))
        )
        (polyline
          (pts
            (xy 8.255 -4.445)
            (xy 7.366 -4.445)
          )
          (stroke (width 0.254) (type default))
          (fill (type background))
        )
        (polyline
          (pts
            (xy 8.255 -3.175)
            (xy 8.255 -4.445)
          )
          (stroke (width 0.254) (type default))
          (fill (type background))
        )
        (polyline
          (pts
            (xy 8.763 -3.175)
            (xy 7.874 -3.175)
          )
          (stroke (width 0.254) (type default))
          (fill (type background))
        )
        (polyline
          (pts
            (xy 12.7 -3.81)
            (xy 11.43 -3.81)
          )
          (stroke (width 0.254) (type default))
          (fill (type background))
        )
        (polyline
          (pts
            (xy 6.35 -1.27)
            (xy 11.43 -3.81)
            (xy 6.35 -6.35)
            (xy 6.35 -1.27)
          )
          (stroke (width 0.254) (type default))
          (fill (type background))
        )
        (rectangle (start 2.54 2.54) (end 15.24 -10.16)
          (stroke (width 0.254) (type default))
          (fill (type background))
        )
        (pin no_connect line (at 15.24 -6.35 180) (length 2.54) hide
          (name "NC" (effects (font (size 1.27 1.27))))
          (number "1" (effects (font (size 1.27 1.27))))
        )
        (pin input line (at 0 -3.81 0) (length 2.54)
          (name "A" (effects (font (size 1.27 1.27))))
          (number "2" (effects (font (size 1.27 1.27))))
        )
        (pin power_in line (at 0 -7.62 0) (length 2.54)
          (name "GND" (effects (font (size 1.27 1.27))))
          (number "3" (effects (font (size 1.27 1.27))))
        )
        (pin output line (at 17.78 -3.81 180) (length 2.54)
          (name "Y" (effects (font (size 1.27 1.27))))
          (number "4" (effects (font (size 1.27 1.27))))
        )
        (pin power_in line (at 0 0 0) (length 2.54)
          (name "VCC" (effects (font (size 1.27 1.27))))
          (number "5" (effects (font (size 1.27 1.27))))
        )
      )
    )
	(symbol "antmicroMechanicalParts:MP_Pad6mm_Drill3.2mm" (pin_names hide) (in_bom no) (on_board yes)
      (property "Reference" "MP" (at 20.32 -2.54 0)
        (effects (font (size 1.27 1.27) (thickness 0.15)) (justify left bottom))
      )
      (property "Value" "MP_Pad6mm_Drill3.2mm" (at 20.32 -5.08 0)
        (effects (font (size 1.27 1.27) (thickness 0.15)) (justify left bottom))
      )
      (property "Footprint" "antmicro-footprints:MP_Pad6mm_Drill3.2mm" (at 20.32 -7.62 0)
        (effects (font (size 1.27 1.27) (thickness 0.15)) (justify left bottom) hide)
      )
      (property "Datasheet" "" (at 16.84 -15.57 0)
        (effects (font (size 1.27 1.27) (thickness 0.15)) (justify left bottom) hide)
      )
      (property "Author" "Antmicro" (at 20.32 -10.16 0)
        (effects (font (size 1.27 1.27) (thickness 0.15)) (justify left bottom) hide)
      )
      (property "License" "Apache-2.0" (at 20.32 -12.7 0)
        (effects (font (size 1.27 1.27) (thickness 0.15)) (justify left bottom) hide)
      )
      (property "ki_keywords" "MECHANICAL" (at 0 0 0)
        (effects (font (size 1.27 1.27)) hide)
      )
      (property "ki_description" "Mechanical part" (at 0 0 0)
        (effects (font (size 1.27 1.27)) hide)
      )
      (symbol "MP_Pad6mm_Drill3.2mm_1_1"
        (circle (center 5.08 0) (radius 1.27)
          (stroke (width 0.254) (type default))
          (fill (type background))
        )
        (circle (center 5.08 0) (radius 2.54)
          (stroke (width 0.254) (type default))
          (fill (type background))
        )
        (pin passive line (at 0 0 0) (length 2.54)
          (name "~" (effects (font (size 1.27 1.27))))
          (number "1" (effects (font (size 1.27 1.27))))
        )
      )
    )
	(symbol "antmicroOptoisolatorsLogicOutput:ACPL-217-500E" (in_bom yes) (on_board yes)
      (property "Reference" "U" (at 27.94 -5.08 0)
        (effects (font (size 1.27 1.27) (thickness 0.15)) (justify left bottom))
      )
      (property "Value" "ACPL-217-500E" (at 27.94 -7.62 0)
        (effects (font (size 1.27 1.27) (thickness 0.15)) (justify left bottom) hide)
      )
      (property "Footprint" "antmicro-footprints:SOIC-4_4.55x2.6mm_P1.27mm" (at 27.94 -10.16 0)
        (effects (font (size 1.27 1.27) (thickness 0.15)) (justify left bottom) hide)
      )
      (property "Datasheet" "https://docs.broadcom.com/doc/AV02-0470EN" (at 27.94 -12.7 0)
        (effects (font (size 1.27 1.27) (thickness 0.15)) (justify left bottom) hide)
      )
      (property "Description" "Broadcom ACPL-217-500E DC Input Transistor Output Optocoupler, Surface Mount, 4-Pin SO" (at 27.94 -15.24 0)
        (effects (font (size 1.27 1.27) (thickness 0.15)) (justify left bottom) hide)
      )
      (property "Manufacturer" "Broadcom" (at 27.94 -17.78 0)
        (effects (font (size 1.27 1.27) (thickness 0.15)) (justify left bottom) hide)
      )
      (property "MPN" "ACPL-217-500E" (at 27.94 -20.32 0)
        (effects (font (size 1.27 1.27) (thickness 0.15)) (justify left bottom))
      )
      (property "Author" "Antmicro" (at 27.94 -22.86 0)
        (effects (font (size 1.27 1.27) (thickness 0.15)) (justify left bottom) hide)
      )
      (property "License" "Apache-2.0" (at 27.94 -25.4 0)
        (effects (font (size 1.27 1.27) (thickness 0.15)) (justify left bottom) hide)
      )
      (property "ki_keywords" "SMT, OPTOCOUPLER, IC" (at 0 0 0)
        (effects (font (size 1.27 1.27)) hide)
      )
      (property "ki_description" "Optocoupler, Transistor Output, 1 Channel, SOIC, 4 Pins, 50 mA, 3 kV, 50 %" (at 0 0 0)
        (effects (font (size 1.27 1.27)) hide)
      )
      (symbol "ACPL-217-500E_1_1"
        (polyline
          (pts
            (xy 3.175 -2.413)
            (xy 4.445 -2.413)
          )
          (stroke (width 0.254) (type default))
          (fill (type background))
        )
        (polyline
          (pts
            (xy 5.207 -2.413)
            (xy 7.239 -2.413)
          )
          (stroke (width 0.254) (type default))
          (fill (type background))
        )
        (polyline
          (pts
            (xy 5.207 -1.397)
            (xy 7.239 -1.397)
          )
          (stroke (width 0.254) (type default))
          (fill (type background))
        )
        (polyline
          (pts
            (xy 7.747 -0.889)
            (xy 7.747 -2.921)
          )
          (stroke (width 0.254) (type default))
          (fill (type background))
        )
        (polyline
          (pts
            (xy 9.017 -3.683)
            (xy 7.747 -2.413)
          )
          (stroke (width 0.254) (type default))
          (fill (type background))
        )
        (polyline
          (pts
            (xy 9.017 -0.127)
            (xy 7.747 -1.397)
          )
          (stroke (width 0.254) (type default))
          (fill (type background))
        )
        (polyline
          (pts
            (xy 9.144 -3.81)
            (xy 8.89 -3.556)
          )
          (stroke (width 0.254) (type default))
          (fill (type background))
        )
        (polyline
          (pts
            (xy 9.144 -3.81)
            (xy 8.89 -3.556)
          )
          (stroke (width 0.254) (type default))
          (fill (type background))
        )
        (polyline
          (pts
            (xy 9.144 0)
            (xy 7.874 -1.27)
          )
          (stroke (width 0.254) (type default))
          (fill (type background))
        )
        (polyline
          (pts
            (xy 10.414 -3.81)
            (xy 9.144 -3.81)
          )
          (stroke (width 0.254) (type default))
          (fill (type background))
        )
        (polyline
          (pts
            (xy 10.414 0)
            (xy 9.144 0)
          )
          (stroke (width 0.254) (type default))
          (fill (type background))
        )
        (polyline
          (pts
            (xy 2.54 -3.81)
            (xy 3.81 -3.81)
            (xy 3.81 -2.54)
          )
          (stroke (width 0.254) (type default))
          (fill (type background))
        )
        (polyline
          (pts
            (xy 2.54 0)
            (xy 3.81 0)
            (xy 3.81 -1.27)
          )
          (stroke (width 0.254) (type default))
          (fill (type background))
        )
        (polyline
          (pts
            (xy 3.175 -1.27)
            (xy 4.445 -1.27)
            (xy 3.81 -2.413)
            (xy 3.175 -1.27)
          )
          (stroke (width 0.254) (type default))
          (fill (type background))
        )
        (polyline
          (pts
            (xy 6.477 -2.159)
            (xy 6.477 -2.159)
            (xy 6.477 -2.667)
            (xy 7.239 -2.413)
            (xy 6.477 -2.159)
            (xy 6.477 -2.159)
          )
          (stroke (width 0.254) (type default))
          (fill (type background))
        )
        (polyline
          (pts
            (xy 6.477 -1.143)
            (xy 6.477 -1.143)
            (xy 6.477 -1.651)
            (xy 7.239 -1.397)
            (xy 6.477 -1.143)
            (xy 6.477 -1.143)
          )
          (stroke (width 0.254) (type default))
          (fill (type background))
        )
        (polyline
          (pts
            (xy 9.017 -3.683)
            (xy 9.017 -3.683)
            (xy 8.89 -3.048)
            (xy 8.382 -3.556)
            (xy 9.017 -3.683)
            (xy 9.017 -3.683)
          )
          (stroke (width 0.254) (type default))
          (fill (type background))
        )
        (rectangle (start 2.54 0.635) (end 2.54 0.635)
          (stroke (width 0.254) (type default))
          (fill (type background))
        )
        (rectangle (start 2.54 1.27) (end 10.414 -5.08)
          (stroke (width 0.254) (type default))
          (fill (type background))
        )
        (pin passive line (at 0 0 0) (length 2.54)
          (name "~" (effects (font (size 1.27 1.27))))
          (number "1" (effects (font (size 1.27 1.27))))
        )
        (pin passive line (at 0 -3.81 0) (length 2.54)
          (name "~" (effects (font (size 1.27 1.27))))
          (number "2" (effects (font (size 1.27 1.27))))
        )
        (pin passive line (at 12.7 -3.81 180) (length 2.54)
          (name "~" (effects (font (size 1.27 1.27))))
          (number "3" (effects (font (size 1.27 1.27))))
        )
        (pin passive line (at 12.7 0 180) (length 2.54)
          (name "~" (effects (font (size 1.27 1.27))))
          (number "4" (effects (font (size 1.27 1.27))))
        )
      )
    )
	(symbol "antmicroOptoisolatorsLogicOutput:ISO1641" (pin_names (offset 1.016)) (in_bom yes) (on_board yes)
      (property "Reference" "U" (at 35.56 -5.08 0)
        (effects (font (size 1.27 1.27) (thickness 0.15)) (justify left bottom))
      )
      (property "Value" "ISO1641" (at 35.56 -10.16 0)
        (effects (font (size 1.27 1.27) (thickness 0.15)) (justify left bottom) hide)
      )
      (property "Footprint" "antmicro-footprints:SOIC-8_3.9x4.9x1.75mm_P1.27mm" (at 35.56 -12.7 0)
        (effects (font (size 1.27 1.27) (thickness 0.15)) (justify left bottom) hide)
      )
      (property "Datasheet" "https://www.ti.com/lit/ds/symlink/iso1641.pdf?ts=1649669035432&ref_url=https%253A%252F%252Fwww.ti.com%252Fproduct%252FISO1641" (at 35.56 -15.24 0)
        (effects (font (size 1.27 1.27) (thickness 0.15)) (justify left bottom) hide)
      )
      (property "MPN" "ISO1641BDR" (at 35.56 -7.62 0)
        (effects (font (size 1.27 1.27) (thickness 0.15)) (justify left bottom))
      )
      (property "Manufacturer" "Texas Instruments" (at 35.56 -17.78 0)
        (effects (font (size 1.27 1.27) (thickness 0.15)) (justify left bottom) hide)
      )
      (property "Author" "Antmicro" (at 35.56 -20.32 0)
        (effects (font (size 1.27 1.27) (thickness 0.15)) (justify left bottom) hide)
      )
      (property "License" "Apache-2.0" (at 35.56 -22.86 0)
        (effects (font (size 1.27 1.27) (thickness 0.15)) (justify left bottom) hide)
      )
      (property "ki_keywords" "SMT, OPTOCOUPLER, IC, INTERFACE, I2C, ISOLATOR" (at 0 0 0)
        (effects (font (size 1.27 1.27)) hide)
      )
      (property "ki_description" "Bidirectional Optoisolator" (at 0 0 0)
        (effects (font (size 1.27 1.27)) hide)
      )
      (symbol "ISO1641_0_1"
        (rectangle (start 2.54 1.27) (end 17.78 -11.43)
          (stroke (width 0) (type default))
          (fill (type background))
        )
      )
      (symbol "ISO1641_1_1"
        (pin power_in line (at 0 0 0) (length 2.54)
          (name "VCC1" (effects (font (size 1.27 1.27))))
          (number "1" (effects (font (size 1.27 1.27))))
        )
        (pin bidirectional line (at 0 -3.81 0) (length 2.54)
          (name "SDA1" (effects (font (size 1.27 1.27))))
          (number "2" (effects (font (size 1.27 1.27))))
        )
        (pin bidirectional line (at 0 -6.35 0) (length 2.54)
          (name "SCL1" (effects (font (size 1.27 1.27))))
          (number "3" (effects (font (size 1.27 1.27))))
        )
        (pin power_in line (at 0 -10.16 0) (length 2.54)
          (name "GND1" (effects (font (size 1.27 1.27))))
          (number "4" (effects (font (size 1.27 1.27))))
        )
        (pin power_in line (at 20.32 -10.16 180) (length 2.54)
          (name "GND2" (effects (font (size 1.27 1.27))))
          (number "5" (effects (font (size 1.27 1.27))))
        )
        (pin bidirectional line (at 20.32 -6.35 180) (length 2.54)
          (name "SCL2" (effects (font (size 1.27 1.27))))
          (number "6" (effects (font (size 1.27 1.27))))
        )
        (pin bidirectional line (at 20.32 -3.81 180) (length 2.54)
          (name "SDA2" (effects (font (size 1.27 1.27))))
          (number "7" (effects (font (size 1.27 1.27))))
        )
        (pin power_in line (at 20.32 0 180) (length 2.54)
          (name "VCC2" (effects (font (size 1.27 1.27))))
          (number "8" (effects (font (size 1.27 1.27))))
        )
      )
    )
	(symbol "antmicroPMICVoltageRegulatorsLinear:NCP163ASN330T1G" (in_bom yes) (on_board yes)
      (property "Reference" "U" (at 35.56 -2.54 0)
        (effects (font (size 1.27 1.27) (thickness 0.15)) (justify left bottom))
      )
      (property "Value" "NCP163ASN330T1G" (at 35.56 -7.62 0)
        (effects (font (size 1.27 1.27) (thickness 0.15)) (justify left bottom) hide)
      )
      (property "Footprint" "antmicro-footprints:SOT-23-5" (at 35.56 -10.16 0)
        (effects (font (size 1.27 1.27) (thickness 0.15)) (justify left bottom) hide)
      )
      (property "Datasheet" "https://mouser.com/datasheet/2/308/1/NCP163_D-2317108.pdf" (at 35.56 -12.7 0)
        (effects (font (size 1.27 1.27) (thickness 0.15)) (justify left bottom) hide)
      )
      (property "MPN" "NCP163ASN330T1G" (at 35.56 -5.08 0)
        (effects (font (size 1.27 1.27) (thickness 0.15)) (justify left bottom))
      )
      (property "Manufacturer" "ON Semiconductor" (at 35.56 -15.24 0)
        (effects (font (size 1.27 1.27) (thickness 0.15)) (justify left bottom) hide)
      )
      (property "Author" "Antmicro" (at 35.56 -17.78 0)
        (effects (font (size 1.27 1.27) (thickness 0.15)) (justify left bottom) hide)
      )
      (property "License" "Apache-2.0" (at 35.56 -20.32 0)
        (effects (font (size 1.27 1.27) (thickness 0.15)) (justify left bottom) hide)
      )
      (property "ki_keywords" "SMT, PMIC, IC, LDO, VOLTAGE, REGULATOR" (at 0 0 0)
        (effects (font (size 1.27 1.27)) hide)
      )
      (property "ki_description" "Fixed LDO Voltage Regulator, 2.2V to 5.5V, 105mV drop, 3.3V/250mA out, SOT-23-5" (at 0 0 0)
        (effects (font (size 1.27 1.27)) hide)
      )
      (symbol "NCP163ASN330T1G_1_1"
        (rectangle (start 2.54 2.54) (end 17.78 -5.08)
          (stroke (width 0.254) (type default))
          (fill (type background))
        )
        (pin power_in line (at 0 0 0) (length 2.54)
          (name "VIN" (effects (font (size 1.27 1.27))))
          (number "1" (effects (font (size 1.27 1.27))))
        )
        (pin power_in line (at 20.32 -2.54 180) (length 2.54)
          (name "GND" (effects (font (size 1.27 1.27))))
          (number "2" (effects (font (size 1.27 1.27))))
        )
        (pin input line (at 0 -2.54 0) (length 2.54)
          (name "EN" (effects (font (size 1.27 1.27))))
          (number "3" (effects (font (size 1.27 1.27))))
        )
        (pin no_connect line (at 17.78 1.27 180) (length 2.54) hide
          (name "NC" (effects (font (size 1.27 1.27))))
          (number "4" (effects (font (size 1.27 1.27))))
        )
        (pin power_out line (at 20.32 0 180) (length 2.54)
          (name "VOUT" (effects (font (size 1.27 1.27))))
          (number "5" (effects (font (size 1.27 1.27))))
        )
      )
    )
	(symbol "antmicroResistors0402:R_0R_0402" (pin_numbers hide) (pin_names hide) (in_bom yes) (on_board yes)
      (property "Reference" "R" (at 20.32 -5.08 0)
        (effects (font (size 1.27 1.27) (thickness 0.15)) (justify left bottom))
      )
      (property "Value" "R_0R_0402" (at 20.32 -12.7 0)
        (effects (font (size 1.27 1.27) (thickness 0.15)) (justify left bottom) hide)
      )
      (property "Footprint" "antmicro-footprints:R_0402_1005Metric" (at 20.32 -15.24 0)
        (effects (font (size 1.27 1.27) (thickness 0.15)) (justify left bottom) hide)
      )
      (property "Datasheet" "https://industrial.panasonic.com/cdbs/www-data/pdf/RDA0000/AOA0000C301.pdf" (at 20.32 -17.78 0)
        (effects (font (size 1.27 1.27) (thickness 0.15)) (justify left bottom) hide)
      )
      (property "MPN" "ERJ2GE0R00X" (at 20.32 -20.32 0)
        (effects (font (size 1.27 1.27) (thickness 0.15)) (justify left bottom) hide)
      )
      (property "Manufacturer" "Panasonic" (at 20.32 -22.86 0)
        (effects (font (size 1.27 1.27) (thickness 0.15)) (justify left bottom) hide)
      )
      (property "License" "Apache-2.0" (at 20.32 -25.4 0)
        (effects (font (size 1.27 1.27) (thickness 0.15)) (justify left bottom) hide)
      )
      (property "Author" "Antmicro" (at 20.32 -27.94 0)
        (effects (font (size 1.27 1.27) (thickness 0.15)) (justify left bottom) hide)
      )
      (property "Val" "0R" (at 20.32 -7.62 0)
        (effects (font (size 1.27 1.27) (thickness 0.15)) (justify left bottom))
      )
      (property "Tolerance" "~" (at 20.32 -10.16 0)
        (effects (font (size 1.27 1.27)) (justify left bottom) hide)
      )
      (property "Current" "1A" (at 20.32 -30.48 0)
        (effects (font (size 1.27 1.27) (thickness 0.15)) (justify left bottom) hide)
      )
      (property "ki_keywords" "0402, SMT, RESISTOR, PASSIVE" (at 0 0 0)
        (effects (font (size 1.27 1.27)) hide)
      )
      (property "ki_description" "SMD Chip Resistor, Jumper, 0 ohm, 100 mW, 0402 [1005 Metric], Thick Film, General Purpose" (at 0 0 0)
        (effects (font (size 1.27 1.27)) hide)
      )
      (symbol "R_0R_0402_0_1"
        (rectangle (start 0.635 0.889) (end 4.445 -0.889)
          (stroke (width 0.254) (type default))
          (fill (type none))
        )
      )
      (symbol "R_0R_0402_1_1"
        (pin passive line (at 0 0 0) (length 0.635)
          (name "~" (effects (font (size 1.27 1.27))))
          (number "1" (effects (font (size 1.27 1.27))))
        )
        (pin passive line (at 5.08 0 180) (length 0.635)
          (name "~" (effects (font (size 1.27 1.27))))
          (number "2" (effects (font (size 1.27 1.27))))
        )
      )
    )
	(symbol "antmicroResistors0402:R_100k_0.1%_0402" (pin_numbers hide) (pin_names hide) (in_bom yes) (on_board yes)
      (property "Reference" "R" (at 20.32 -5.08 0)
        (effects (font (size 1.27 1.27) (thickness 0.15)) (justify left bottom))
      )
      (property "Value" "R_100k_0.1%_0402" (at 20.32 -12.7 0)
        (effects (font (size 1.27 1.27) (thickness 0.15)) (justify left bottom) hide)
      )
      (property "Footprint" "antmicro-footprints:R_0402_1005Metric" (at 20.32 -15.24 0)
        (effects (font (size 1.27 1.27) (thickness 0.15)) (justify left bottom) hide)
      )
      (property "Datasheet" "https://www.mouser.pl/datasheet/2/447/PYu_RC_Group_51_RoHS_L_11-1984063.pdf" (at 20.32 -17.78 0)
        (effects (font (size 1.27 1.27) (thickness 0.15)) (justify left bottom) hide)
      )
      (property "MPN" "RC0402BR-07100KL" (at 20.32 -20.32 0)
        (effects (font (size 1.27 1.27) (thickness 0.15)) (justify left bottom) hide)
      )
      (property "Manufacturer" "Yageo" (at 20.32 -22.86 0)
        (effects (font (size 1.27 1.27) (thickness 0.15)) (justify left bottom) hide)
      )
      (property "License" "Apache-2.0" (at 20.32 -25.4 0)
        (effects (font (size 1.27 1.27) (thickness 0.15)) (justify left bottom) hide)
      )
      (property "Author" "Antmicro" (at 20.32 -27.94 0)
        (effects (font (size 1.27 1.27) (thickness 0.15)) (justify left bottom) hide)
      )
      (property "Val" "100k" (at 20.32 -7.62 0)
        (effects (font (size 1.27 1.27) (thickness 0.15)) (justify left bottom))
      )
      (property "Tolerance" "0.1%" (at 20.32 -10.16 0)
        (effects (font (size 1.27 1.27)) (justify left bottom) hide)
      )
      (property "ki_keywords" "0402, SMT, RESISTOR, PASSIVE" (at 0 0 0)
        (effects (font (size 1.27 1.27)) hide)
      )
      (property "ki_description" "SMD Chip Resistor, 100 kohm, ± 0.1%, 63 mW, 0402 [1005 Metric], Thin Film" (at 0 0 0)
        (effects (font (size 1.27 1.27)) hide)
      )
      (symbol "R_100k_0.1%_0402_0_1"
        (rectangle (start 0.635 0.889) (end 4.445 -0.889)
          (stroke (width 0.254) (type default))
          (fill (type none))
        )
      )
      (symbol "R_100k_0.1%_0402_1_1"
        (pin passive line (at 0 0 0) (length 0.635)
          (name "~" (effects (font (size 1.27 1.27))))
          (number "1" (effects (font (size 1.27 1.27))))
        )
        (pin passive line (at 5.08 0 180) (length 0.635)
          (name "~" (effects (font (size 1.27 1.27))))
          (number "2" (effects (font (size 1.27 1.27))))
        )
      )
    )
	(symbol "antmicroResistors0402:R_10k_0402" (pin_numbers hide) (pin_names hide) (in_bom yes) (on_board yes)
      (property "Reference" "R" (at 20.32 -5.08 0)
        (effects (font (size 1.27 1.27) (thickness 0.15)) (justify left bottom))
      )
      (property "Value" "R_10k_0402" (at 20.32 -12.7 0)
        (effects (font (size 1.27 1.27) (thickness 0.15)) (justify left bottom) hide)
      )
      (property "Footprint" "antmicro-footprints:R_0402_1005Metric" (at 20.32 -15.24 0)
        (effects (font (size 1.27 1.27) (thickness 0.15)) (justify left bottom) hide)
      )
      (property "Datasheet" "https://www.bourns.com/docs/product-datasheets/cr.pdf" (at 20.32 -17.78 0)
        (effects (font (size 1.27 1.27) (thickness 0.15)) (justify left bottom) hide)
      )
      (property "MPN" "CR0402-FX-1002GLF" (at 20.32 -20.32 0)
        (effects (font (size 1.27 1.27) (thickness 0.15)) (justify left bottom) hide)
      )
      (property "Manufacturer" "Bourns" (at 20.32 -22.86 0)
        (effects (font (size 1.27 1.27) (thickness 0.15)) (justify left bottom) hide)
      )
      (property "License" "Apache-2.0" (at 20.32 -25.4 0)
        (effects (font (size 1.27 1.27) (thickness 0.15)) (justify left bottom) hide)
      )
      (property "Author" "Antmicro" (at 20.32 -27.94 0)
        (effects (font (size 1.27 1.27) (thickness 0.15)) (justify left bottom) hide)
      )
      (property "Val" "10k" (at 20.32 -7.62 0)
        (effects (font (size 1.27 1.27) (thickness 0.15)) (justify left bottom))
      )
      (property "Tolerance" "1%" (at 20.32 -10.16 0)
        (effects (font (size 1.27 1.27)) (justify left bottom) hide)
      )
      (property "ki_keywords" "0402, SMT, RESISTOR, PASSIVE" (at 0 0 0)
        (effects (font (size 1.27 1.27)) hide)
      )
      (property "ki_description" "SMD Chip Resistor, 10 kohm, ± 1%, 62.5 mW, 0402 [1005 Metric], Thick Film, General Purpose" (at 0 0 0)
        (effects (font (size 1.27 1.27)) hide)
      )
      (symbol "R_10k_0402_0_1"
        (rectangle (start 0.635 0.889) (end 4.445 -0.889)
          (stroke (width 0.254) (type default))
          (fill (type none))
        )
      )
      (symbol "R_10k_0402_1_1"
        (pin passive line (at 0 0 0) (length 0.635)
          (name "~" (effects (font (size 1.27 1.27))))
          (number "1" (effects (font (size 1.27 1.27))))
        )
        (pin passive line (at 5.08 0 180) (length 0.635)
          (name "~" (effects (font (size 1.27 1.27))))
          (number "2" (effects (font (size 1.27 1.27))))
        )
      )
    )
	(symbol "antmicroResistors0402:R_12k_0402" (pin_numbers hide) (pin_names hide) (in_bom yes) (on_board yes)
      (property "Reference" "R" (at 20.32 -5.08 0)
        (effects (font (size 1.27 1.27) (thickness 0.15)) (justify left bottom))
      )
      (property "Value" "R_12k_0402" (at 20.32 -12.7 0)
        (effects (font (size 1.27 1.27) (thickness 0.15)) (justify left bottom) hide)
      )
      (property "Footprint" "antmicro-footprints:R_0402_1005Metric" (at 20.32 -15.24 0)
        (effects (font (size 1.27 1.27) (thickness 0.15)) (justify left bottom) hide)
      )
      (property "Datasheet" "https://www.bourns.com/docs/product-datasheets/cr.pdf" (at 20.32 -17.78 0)
        (effects (font (size 1.27 1.27) (thickness 0.15)) (justify left bottom) hide)
      )
      (property "MPN" "CR0402-FX-1202GLF" (at 20.32 -20.32 0)
        (effects (font (size 1.27 1.27) (thickness 0.15)) (justify left bottom) hide)
      )
      (property "Manufacturer" "Bourns" (at 20.32 -22.86 0)
        (effects (font (size 1.27 1.27) (thickness 0.15)) (justify left bottom) hide)
      )
      (property "License" "Apache-2.0" (at 20.32 -25.4 0)
        (effects (font (size 1.27 1.27) (thickness 0.15)) (justify left bottom) hide)
      )
      (property "Author" "Antmicro" (at 20.32 -27.94 0)
        (effects (font (size 1.27 1.27) (thickness 0.15)) (justify left bottom) hide)
      )
      (property "Val" "12k" (at 20.32 -7.62 0)
        (effects (font (size 1.27 1.27) (thickness 0.15)) (justify left bottom))
      )
      (property "Tolerance" "1%" (at 20.32 -10.16 0)
        (effects (font (size 1.27 1.27)) (justify left bottom) hide)
      )
      (property "ki_keywords" "0402, SMT, RESISTOR, PASSIVE" (at 0 0 0)
        (effects (font (size 1.27 1.27)) hide)
      )
      (property "ki_description" "SMD Chip Resistor, 12 kohm, ± 1%, 62.5 mW, 0402 [1005 Metric], Thick Film, General Purpose" (at 0 0 0)
        (effects (font (size 1.27 1.27)) hide)
      )
      (symbol "R_12k_0402_0_1"
        (rectangle (start 0.635 0.889) (end 4.445 -0.889)
          (stroke (width 0.254) (type default))
          (fill (type none))
        )
      )
      (symbol "R_12k_0402_1_1"
        (pin passive line (at 0 0 0) (length 0.635)
          (name "~" (effects (font (size 1.27 1.27))))
          (number "1" (effects (font (size 1.27 1.27))))
        )
        (pin passive line (at 5.08 0 180) (length 0.635)
          (name "~" (effects (font (size 1.27 1.27))))
          (number "2" (effects (font (size 1.27 1.27))))
        )
      )
    )
	(symbol "antmicroResistors0402:R_15k4_0.1%_0402" (pin_numbers hide) (pin_names hide) (in_bom yes) (on_board yes)
      (property "Reference" "R" (at 20.32 -5.08 0)
        (effects (font (size 1.27 1.27) (thickness 0.15)) (justify left bottom))
      )
      (property "Value" "R_15k4_0.1%_0402" (at 20.32 -12.7 0)
        (effects (font (size 1.27 1.27) (thickness 0.15)) (justify left bottom) hide)
      )
      (property "Footprint" "antmicro-footprints:R_0402_1005Metric" (at 20.32 -15.24 0)
        (effects (font (size 1.27 1.27) (thickness 0.15)) (justify left bottom) hide)
      )
      (property "Datasheet" "https://www.mouser.pl/datasheet/2/315/AOA0000C307-1149632.pdf" (at 20.32 -17.78 0)
        (effects (font (size 1.27 1.27) (thickness 0.15)) (justify left bottom) hide)
      )
      (property "MPN" "ERA-2AEB1542X" (at 20.32 -20.32 0)
        (effects (font (size 1.27 1.27) (thickness 0.15)) (justify left bottom) hide)
      )
      (property "Manufacturer" "Panasonic" (at 20.32 -22.86 0)
        (effects (font (size 1.27 1.27) (thickness 0.15)) (justify left bottom) hide)
      )
      (property "License" "Apache-2.0" (at 20.32 -25.4 0)
        (effects (font (size 1.27 1.27) (thickness 0.15)) (justify left bottom) hide)
      )
      (property "Author" "Antmicro" (at 20.32 -27.94 0)
        (effects (font (size 1.27 1.27) (thickness 0.15)) (justify left bottom) hide)
      )
      (property "Val" "15k4" (at 20.32 -7.62 0)
        (effects (font (size 1.27 1.27) (thickness 0.15)) (justify left bottom))
      )
      (property "Tolerance" "0.1%" (at 20.32 -10.16 0)
        (effects (font (size 1.27 1.27)) (justify left bottom) hide)
      )
      (property "ki_keywords" "0402, SMT, RESISTOR, PASSIVE" (at 0 0 0)
        (effects (font (size 1.27 1.27)) hide)
      )
      (property "ki_description" "SMD Chip Resistor, 15.4 kohm, ± 0.1%, 63 mW, 0402 [1005 Metric], Thin Film" (at 0 0 0)
        (effects (font (size 1.27 1.27)) hide)
      )
      (symbol "R_15k4_0.1%_0402_0_1"
        (rectangle (start 0.635 0.889) (end 4.445 -0.889)
          (stroke (width 0.254) (type default))
          (fill (type none))
        )
      )
      (symbol "R_15k4_0.1%_0402_1_1"
        (pin passive line (at 0 0 0) (length 0.635)
          (name "~" (effects (font (size 1.27 1.27))))
          (number "1" (effects (font (size 1.27 1.27))))
        )
        (pin passive line (at 5.08 0 180) (length 0.635)
          (name "~" (effects (font (size 1.27 1.27))))
          (number "2" (effects (font (size 1.27 1.27))))
        )
      )
    )
	(symbol "antmicroResistors0402:R_1k3_0402" (pin_numbers hide) (pin_names hide) (in_bom yes) (on_board yes)
      (property "Reference" "R" (at 20.32 -5.08 0)
        (effects (font (size 1.27 1.27) (thickness 0.15)) (justify left bottom))
      )
      (property "Value" "R_1k3_0402" (at 20.32 -12.7 0)
        (effects (font (size 1.27 1.27) (thickness 0.15)) (justify left bottom) hide)
      )
      (property "Footprint" "antmicro-footprints:R_0402_1005Metric" (at 20.32 -15.24 0)
        (effects (font (size 1.27 1.27) (thickness 0.15)) (justify left bottom) hide)
      )
      (property "Datasheet" "https://www.bourns.com/docs/product-datasheets/cr.pdf" (at 20.32 -17.78 0)
        (effects (font (size 1.27 1.27) (thickness 0.15)) (justify left bottom) hide)
      )
      (property "MPN" "CR0402-FX-1301GLF" (at 20.32 -20.32 0)
        (effects (font (size 1.27 1.27) (thickness 0.15)) (justify left bottom) hide)
      )
      (property "Manufacturer" "Bourns" (at 20.32 -22.86 0)
        (effects (font (size 1.27 1.27) (thickness 0.15)) (justify left bottom) hide)
      )
      (property "License" "Apache-2.0" (at 20.32 -25.4 0)
        (effects (font (size 1.27 1.27) (thickness 0.15)) (justify left bottom) hide)
      )
      (property "Author" "Antmicro" (at 20.32 -27.94 0)
        (effects (font (size 1.27 1.27) (thickness 0.15)) (justify left bottom) hide)
      )
      (property "Val" "1k3" (at 20.32 -7.62 0)
        (effects (font (size 1.27 1.27) (thickness 0.15)) (justify left bottom))
      )
      (property "Tolerance" "1%" (at 20.32 -10.16 0)
        (effects (font (size 1.27 1.27)) (justify left bottom) hide)
      )
      (property "ki_keywords" "0402, SMT, RESISTOR, PASSIVE" (at 0 0 0)
        (effects (font (size 1.27 1.27)) hide)
      )
      (property "ki_description" "SMD Chip Resistor, 1.3 kohm, ± 1%, 62.5 mW, 0402 [1005 Metric], Thick Film, General Purpose" (at 0 0 0)
        (effects (font (size 1.27 1.27)) hide)
      )
      (symbol "R_1k3_0402_0_1"
        (rectangle (start 0.635 0.889) (end 4.445 -0.889)
          (stroke (width 0.254) (type default))
          (fill (type none))
        )
      )
      (symbol "R_1k3_0402_1_1"
        (pin passive line (at 0 0 0) (length 0.635)
          (name "~" (effects (font (size 1.27 1.27))))
          (number "1" (effects (font (size 1.27 1.27))))
        )
        (pin passive line (at 5.08 0 180) (length 0.635)
          (name "~" (effects (font (size 1.27 1.27))))
          (number "2" (effects (font (size 1.27 1.27))))
        )
      )
    )
	(symbol "antmicroResistors0402:R_1k_0402" (pin_numbers hide) (pin_names hide) (in_bom yes) (on_board yes)
      (property "Reference" "R" (at 20.32 -5.08 0)
        (effects (font (size 1.27 1.27) (thickness 0.15)) (justify left bottom))
      )
      (property "Value" "R_1k_0402" (at 20.32 -12.7 0)
        (effects (font (size 1.27 1.27) (thickness 0.15)) (justify left bottom) hide)
      )
      (property "Footprint" "antmicro-footprints:R_0402_1005Metric" (at 20.32 -15.24 0)
        (effects (font (size 1.27 1.27) (thickness 0.15)) (justify left bottom) hide)
      )
      (property "Datasheet" "https://www.bourns.com/docs/product-datasheets/cr.pdf" (at 20.32 -17.78 0)
        (effects (font (size 1.27 1.27) (thickness 0.15)) (justify left bottom) hide)
      )
      (property "MPN" "CR0402-FX-1001GLF" (at 20.32 -20.32 0)
        (effects (font (size 1.27 1.27) (thickness 0.15)) (justify left bottom) hide)
      )
      (property "Manufacturer" "Bourns" (at 20.32 -22.86 0)
        (effects (font (size 1.27 1.27) (thickness 0.15)) (justify left bottom) hide)
      )
      (property "License" "Apache-2.0" (at 20.32 -25.4 0)
        (effects (font (size 1.27 1.27) (thickness 0.15)) (justify left bottom) hide)
      )
      (property "Author" "Antmicro" (at 20.32 -27.94 0)
        (effects (font (size 1.27 1.27) (thickness 0.15)) (justify left bottom) hide)
      )
      (property "Val" "1k" (at 20.32 -7.62 0)
        (effects (font (size 1.27 1.27) (thickness 0.15)) (justify left bottom))
      )
      (property "Tolerance" "1%" (at 20.32 -10.16 0)
        (effects (font (size 1.27 1.27)) (justify left bottom) hide)
      )
      (property "ki_keywords" "0402, SMT, RESISTOR, PASSIVE" (at 0 0 0)
        (effects (font (size 1.27 1.27)) hide)
      )
      (property "ki_description" "SMD Chip Resistor, 1 kohm, ± 1%, 63 mW, 0402 [1005 Metric], Thick Film, General Purpose" (at 0 0 0)
        (effects (font (size 1.27 1.27)) hide)
      )
      (symbol "R_1k_0402_0_1"
        (rectangle (start 0.635 0.889) (end 4.445 -0.889)
          (stroke (width 0.254) (type default))
          (fill (type none))
        )
      )
      (symbol "R_1k_0402_1_1"
        (pin passive line (at 0 0 0) (length 0.635)
          (name "~" (effects (font (size 1.27 1.27))))
          (number "1" (effects (font (size 1.27 1.27))))
        )
        (pin passive line (at 5.08 0 180) (length 0.635)
          (name "~" (effects (font (size 1.27 1.27))))
          (number "2" (effects (font (size 1.27 1.27))))
        )
      )
    )
	(symbol "antmicroResistors0402:R_220R_0402" (pin_numbers hide) (pin_names hide) (in_bom yes) (on_board yes)
      (property "Reference" "R" (at 20.32 -5.08 0)
        (effects (font (size 1.27 1.27) (thickness 0.15)) (justify left bottom))
      )
      (property "Value" "R_220R_0402" (at 20.32 -12.7 0)
        (effects (font (size 1.27 1.27) (thickness 0.15)) (justify left bottom) hide)
      )
      (property "Footprint" "antmicro-footprints:R_0402_1005Metric" (at 20.32 -15.24 0)
        (effects (font (size 1.27 1.27) (thickness 0.15)) (justify left bottom) hide)
      )
      (property "Datasheet" "https://www.bourns.com/docs/product-datasheets/cr.pdf" (at 20.32 -17.78 0)
        (effects (font (size 1.27 1.27) (thickness 0.15)) (justify left bottom) hide)
      )
      (property "MPN" "CR0402-FX-2200GLF" (at 20.32 -20.32 0)
        (effects (font (size 1.27 1.27) (thickness 0.15)) (justify left bottom) hide)
      )
      (property "Manufacturer" "Bourns" (at 20.32 -22.86 0)
        (effects (font (size 1.27 1.27) (thickness 0.15)) (justify left bottom) hide)
      )
      (property "License" "Apache-2.0" (at 20.32 -25.4 0)
        (effects (font (size 1.27 1.27) (thickness 0.15)) (justify left bottom) hide)
      )
      (property "Author" "Antmicro" (at 20.32 -27.94 0)
        (effects (font (size 1.27 1.27) (thickness 0.15)) (justify left bottom) hide)
      )
      (property "Val" "220R" (at 20.32 -7.62 0)
        (effects (font (size 1.27 1.27) (thickness 0.15)) (justify left bottom))
      )
      (property "Tolerance" "1%" (at 20.32 -10.16 0)
        (effects (font (size 1.27 1.27)) (justify left bottom) hide)
      )
      (property "ki_keywords" "0402, SMT, RESISTOR, PASSIVE" (at 0 0 0)
        (effects (font (size 1.27 1.27)) hide)
      )
      (property "ki_description" "SMD Chip Resistor, 220 ohm, ± 1%, 62.5 mW, 0402 [1005 Metric], Thick Film, General Purpose" (at 0 0 0)
        (effects (font (size 1.27 1.27)) hide)
      )
      (symbol "R_220R_0402_0_1"
        (rectangle (start 0.635 0.889) (end 4.445 -0.889)
          (stroke (width 0.254) (type default))
          (fill (type none))
        )
      )
      (symbol "R_220R_0402_1_1"
        (pin passive line (at 0 0 0) (length 0.635)
          (name "~" (effects (font (size 1.27 1.27))))
          (number "1" (effects (font (size 1.27 1.27))))
        )
        (pin passive line (at 5.08 0 180) (length 0.635)
          (name "~" (effects (font (size 1.27 1.27))))
          (number "2" (effects (font (size 1.27 1.27))))
        )
      )
    )
	(symbol "antmicroResistors0402:R_2k15_0402" (pin_numbers hide) (pin_names hide) (in_bom yes) (on_board yes)
      (property "Reference" "R" (at 15.24 -5.08 0)
        (effects (font (size 1.27 1.27) (thickness 0.15)) (justify left bottom))
      )
      (property "Value" "R_2k15_0402" (at 15.24 -10.16 0)
        (effects (font (size 1.27 1.27) (thickness 0.15)) (justify left bottom) hide)
      )
      (property "Footprint" "antmicro-footprints:R_0402_1005Metric" (at 15.24 -12.7 0)
        (effects (font (size 1.27 1.27) (thickness 0.15)) (justify left bottom) hide)
      )
      (property "Datasheet" "https://www.mouser.com/datasheet/2/54/cr-1858361.pdf" (at 15.24 -15.24 0)
        (effects (font (size 1.27 1.27) (thickness 0.15)) (justify left bottom) hide)
      )
      (property "MPN" "CR0402-FX-2151GLF" (at 15.24 -17.78 0)
        (effects (font (size 1.27 1.27) (thickness 0.15)) (justify left bottom) hide)
      )
      (property "Val" "2k15" (at 15.24 -7.62 0)
        (effects (font (size 1.27 1.27) (thickness 0.15)) (justify left bottom))
      )
      (property "Tolerance" "1%" (at 15.24 -20.32 0)
        (effects (font (size 1.27 1.27) (thickness 0.15)) (justify left bottom) hide)
      )
      (property "Manufacturer" "Bourns" (at 15.24 -22.86 0)
        (effects (font (size 1.27 1.27) (thickness 0.15)) (justify left bottom) hide)
      )
      (property "Author" "Antmicro" (at 15.24 -25.4 0)
        (effects (font (size 1.27 1.27) (thickness 0.15)) (justify left bottom) hide)
      )
      (property "License" "Apache-2.0" (at 15.24 -27.94 0)
        (effects (font (size 1.27 1.27) (thickness 0.15)) (justify left bottom) hide)
      )
      (property "ki_keywords" "0402, SMT, RESISTOR, PASSIVE" (at 0 0 0)
        (effects (font (size 1.27 1.27)) hide)
      )
      (property "ki_description" "SMD Chip Resistor, 2.15 kohm, ± 1%, 63 mW, 0402 [1005 Metric], Thick Film, General Purpose" (at 0 0 0)
        (effects (font (size 1.27 1.27)) hide)
      )
      (symbol "R_2k15_0402_0_1"
        (rectangle (start 0.635 0.889) (end 4.445 -0.889)
          (stroke (width 0.254) (type default))
          (fill (type none))
        )
      )
      (symbol "R_2k15_0402_1_1"
        (pin passive line (at 0 0 0) (length 0.635)
          (name "~" (effects (font (size 1.27 1.27))))
          (number "1" (effects (font (size 1.27 1.27))))
        )
        (pin passive line (at 5.08 0 180) (length 0.635)
          (name "~" (effects (font (size 1.27 1.27))))
          (number "2" (effects (font (size 1.27 1.27))))
        )
      )
    )
	(symbol "antmicroResistors0402:R_330R_0402" (pin_numbers hide) (pin_names hide) (in_bom yes) (on_board yes)
      (property "Reference" "R" (at 20.32 -5.08 0)
        (effects (font (size 1.27 1.27) (thickness 0.15)) (justify left bottom))
      )
      (property "Value" "R_330R_0402" (at 20.32 -12.7 0)
        (effects (font (size 1.27 1.27) (thickness 0.15)) (justify left bottom) hide)
      )
      (property "Footprint" "antmicro-footprints:R_0402_1005Metric" (at 20.32 -15.24 0)
        (effects (font (size 1.27 1.27) (thickness 0.15)) (justify left bottom) hide)
      )
      (property "Datasheet" "https://www.bourns.com/docs/product-datasheets/cr.pdf" (at 20.32 -17.78 0)
        (effects (font (size 1.27 1.27) (thickness 0.15)) (justify left bottom) hide)
      )
      (property "MPN" "CR0402-FX-3300GLF" (at 20.32 -20.32 0)
        (effects (font (size 1.27 1.27) (thickness 0.15)) (justify left bottom) hide)
      )
      (property "Manufacturer" "Bourns" (at 20.32 -22.86 0)
        (effects (font (size 1.27 1.27) (thickness 0.15)) (justify left bottom) hide)
      )
      (property "License" "Apache-2.0" (at 20.32 -25.4 0)
        (effects (font (size 1.27 1.27) (thickness 0.15)) (justify left bottom) hide)
      )
      (property "Author" "Antmicro" (at 20.32 -27.94 0)
        (effects (font (size 1.27 1.27) (thickness 0.15)) (justify left bottom) hide)
      )
      (property "Val" "330R" (at 20.32 -7.62 0)
        (effects (font (size 1.27 1.27) (thickness 0.15)) (justify left bottom))
      )
      (property "Tolerance" "1%" (at 20.32 -10.16 0)
        (effects (font (size 1.27 1.27)) (justify left bottom) hide)
      )
      (property "ki_keywords" "0402, SMT, RESISTOR, PASSIVE" (at 0 0 0)
        (effects (font (size 1.27 1.27)) hide)
      )
      (property "ki_description" "SMD Chip Resistor, 330 ohm, ± 1%, 62.5 mW, 0402 [1005 Metric], Thick Film, General Purpose" (at 0 0 0)
        (effects (font (size 1.27 1.27)) hide)
      )
      (symbol "R_330R_0402_0_1"
        (rectangle (start 0.635 0.889) (end 4.445 -0.889)
          (stroke (width 0.254) (type default))
          (fill (type none))
        )
      )
      (symbol "R_330R_0402_1_1"
        (pin passive line (at 0 0 0) (length 0.635)
          (name "~" (effects (font (size 1.27 1.27))))
          (number "1" (effects (font (size 1.27 1.27))))
        )
        (pin passive line (at 5.08 0 180) (length 0.635)
          (name "~" (effects (font (size 1.27 1.27))))
          (number "2" (effects (font (size 1.27 1.27))))
        )
      )
    )
	(symbol "antmicroResistors0402:R_4k7_0402" (pin_numbers hide) (pin_names hide) (in_bom yes) (on_board yes)
      (property "Reference" "R" (at 20.32 -5.08 0)
        (effects (font (size 1.27 1.27) (thickness 0.15)) (justify left bottom))
      )
      (property "Value" "R_4k7_0402" (at 20.32 -12.7 0)
        (effects (font (size 1.27 1.27) (thickness 0.15)) (justify left bottom) hide)
      )
      (property "Footprint" "antmicro-footprints:R_0402_1005Metric" (at 20.32 -15.24 0)
        (effects (font (size 1.27 1.27) (thickness 0.15)) (justify left bottom) hide)
      )
      (property "Datasheet" "https://www.bourns.com/docs/product-datasheets/cr.pdf" (at 20.32 -17.78 0)
        (effects (font (size 1.27 1.27) (thickness 0.15)) (justify left bottom) hide)
      )
      (property "MPN" "CR0402-FX-4701GLF" (at 20.32 -20.32 0)
        (effects (font (size 1.27 1.27) (thickness 0.15)) (justify left bottom) hide)
      )
      (property "Manufacturer" "Bourns" (at 20.32 -22.86 0)
        (effects (font (size 1.27 1.27) (thickness 0.15)) (justify left bottom) hide)
      )
      (property "License" "Apache-2.0" (at 20.32 -25.4 0)
        (effects (font (size 1.27 1.27) (thickness 0.15)) (justify left bottom) hide)
      )
      (property "Author" "Antmicro" (at 20.32 -27.94 0)
        (effects (font (size 1.27 1.27) (thickness 0.15)) (justify left bottom) hide)
      )
      (property "Val" "4k7" (at 20.32 -7.62 0)
        (effects (font (size 1.27 1.27) (thickness 0.15)) (justify left bottom))
      )
      (property "Tolerance" "1%" (at 20.32 -10.16 0)
        (effects (font (size 1.27 1.27)) (justify left bottom) hide)
      )
      (property "ki_keywords" "0402, SMT, RESISTOR, PASSIVE" (at 0 0 0)
        (effects (font (size 1.27 1.27)) hide)
      )
      (property "ki_description" "SMD Chip Resistor, 4.7 kohm, ± 1%, 62.5 mW, 0402 [1005 Metric], Thick Film, General Purpose" (at 0 0 0)
        (effects (font (size 1.27 1.27)) hide)
      )
      (symbol "R_4k7_0402_0_1"
        (rectangle (start 0.635 0.889) (end 4.445 -0.889)
          (stroke (width 0.254) (type default))
          (fill (type none))
        )
      )
      (symbol "R_4k7_0402_1_1"
        (pin passive line (at 0 0 0) (length 0.635)
          (name "~" (effects (font (size 1.27 1.27))))
          (number "1" (effects (font (size 1.27 1.27))))
        )
        (pin passive line (at 5.08 0 180) (length 0.635)
          (name "~" (effects (font (size 1.27 1.27))))
          (number "2" (effects (font (size 1.27 1.27))))
        )
      )
    )
	(symbol "antmicroResistors0402:R_5k1_0402" (pin_numbers hide) (pin_names hide) (in_bom yes) (on_board yes)
      (property "Reference" "R" (at 20.32 -5.08 0)
        (effects (font (size 1.27 1.27) (thickness 0.15)) (justify left bottom))
      )
      (property "Value" "R_5k1_0402" (at 20.32 -12.7 0)
        (effects (font (size 1.27 1.27) (thickness 0.15)) (justify left bottom) hide)
      )
      (property "Footprint" "antmicro-footprints:R_0402_1005Metric" (at 20.32 -15.24 0)
        (effects (font (size 1.27 1.27) (thickness 0.15)) (justify left bottom) hide)
      )
      (property "Datasheet" "https://www.bourns.com/docs/product-datasheets/cr.pdf" (at 20.32 -17.78 0)
        (effects (font (size 1.27 1.27) (thickness 0.15)) (justify left bottom) hide)
      )
      (property "MPN" "CR0402-FX-5101GLF" (at 20.32 -20.32 0)
        (effects (font (size 1.27 1.27) (thickness 0.15)) (justify left bottom) hide)
      )
      (property "Manufacturer" "Bourns" (at 20.32 -22.86 0)
        (effects (font (size 1.27 1.27) (thickness 0.15)) (justify left bottom) hide)
      )
      (property "License" "Apache-2.0" (at 20.32 -25.4 0)
        (effects (font (size 1.27 1.27) (thickness 0.15)) (justify left bottom) hide)
      )
      (property "Author" "Antmicro" (at 20.32 -27.94 0)
        (effects (font (size 1.27 1.27) (thickness 0.15)) (justify left bottom) hide)
      )
      (property "Val" "5k1" (at 20.32 -7.62 0)
        (effects (font (size 1.27 1.27) (thickness 0.15)) (justify left bottom))
      )
      (property "Tolerance" "1%" (at 20.32 -10.16 0)
        (effects (font (size 1.27 1.27)) (justify left bottom) hide)
      )
      (property "ki_keywords" "0402, SMT, RESISTOR, PASSIVE" (at 0 0 0)
        (effects (font (size 1.27 1.27)) hide)
      )
      (property "ki_description" "SMD Chip Resistor, 5.1 kohm, ± 1%, 63 mW, 0402 [1005 Metric], Thick Film, General Purpose" (at 0 0 0)
        (effects (font (size 1.27 1.27)) hide)
      )
      (symbol "R_5k1_0402_0_1"
        (rectangle (start 0.635 0.889) (end 4.445 -0.889)
          (stroke (width 0.254) (type default))
          (fill (type none))
        )
      )
      (symbol "R_5k1_0402_1_1"
        (pin passive line (at 0 0 0) (length 0.635)
          (name "~" (effects (font (size 1.27 1.27))))
          (number "1" (effects (font (size 1.27 1.27))))
        )
        (pin passive line (at 5.08 0 180) (length 0.635)
          (name "~" (effects (font (size 1.27 1.27))))
          (number "2" (effects (font (size 1.27 1.27))))
        )
      )
    )
	(symbol "antmicroResistors0402:R_680R_0402" (pin_numbers hide) (pin_names hide) (in_bom yes) (on_board yes)
      (property "Reference" "R" (at 20.32 -5.08 0)
        (effects (font (size 1.27 1.27) (thickness 0.15)) (justify left bottom))
      )
      (property "Value" "R_680R_0402" (at 20.32 -12.7 0)
        (effects (font (size 1.27 1.27) (thickness 0.15)) (justify left bottom) hide)
      )
      (property "Footprint" "antmicro-footprints:R_0402_1005Metric" (at 20.32 -15.24 0)
        (effects (font (size 1.27 1.27) (thickness 0.15)) (justify left bottom) hide)
      )
      (property "Datasheet" "https://www.bourns.com/docs/product-datasheets/cr.pdf" (at 20.32 -17.78 0)
        (effects (font (size 1.27 1.27) (thickness 0.15)) (justify left bottom) hide)
      )
      (property "MPN" "CR0402-FX-6800GLF" (at 20.32 -20.32 0)
        (effects (font (size 1.27 1.27) (thickness 0.15)) (justify left bottom) hide)
      )
      (property "Manufacturer" "Bourns" (at 20.32 -22.86 0)
        (effects (font (size 1.27 1.27) (thickness 0.15)) (justify left bottom) hide)
      )
      (property "License" "Apache-2.0" (at 20.32 -25.4 0)
        (effects (font (size 1.27 1.27) (thickness 0.15)) (justify left bottom) hide)
      )
      (property "Author" "Antmicro" (at 20.32 -27.94 0)
        (effects (font (size 1.27 1.27) (thickness 0.15)) (justify left bottom) hide)
      )
      (property "Val" "680R" (at 20.32 -7.62 0)
        (effects (font (size 1.27 1.27) (thickness 0.15)) (justify left bottom))
      )
      (property "Tolerance" "1%" (at 20.32 -10.16 0)
        (effects (font (size 1.27 1.27)) (justify left bottom) hide)
      )
      (property "ki_keywords" "0402, SMT, RESISTOR, PASSIVE" (at 0 0 0)
        (effects (font (size 1.27 1.27)) hide)
      )
      (property "ki_description" "SMD Chip Resistor, 680 ohm, ± 1%, 63 mW, 0402 [1005 Metric], Thick Film, General Purpose" (at 0 0 0)
        (effects (font (size 1.27 1.27)) hide)
      )
      (symbol "R_680R_0402_0_1"
        (rectangle (start 0.635 0.889) (end 4.445 -0.889)
          (stroke (width 0.254) (type default))
          (fill (type none))
        )
      )
      (symbol "R_680R_0402_1_1"
        (pin passive line (at 0 0 0) (length 0.635)
          (name "~" (effects (font (size 1.27 1.27))))
          (number "1" (effects (font (size 1.27 1.27))))
        )
        (pin passive line (at 5.08 0 180) (length 0.635)
          (name "~" (effects (font (size 1.27 1.27))))
          (number "2" (effects (font (size 1.27 1.27))))
        )
      )
    )
	(symbol "antmicroResistors0402:R_6k8_0402" (pin_numbers hide) (pin_names hide) (in_bom yes) (on_board yes)
      (property "Reference" "R" (at 20.32 -5.08 0)
        (effects (font (size 1.27 1.27) (thickness 0.15)) (justify left bottom))
      )
      (property "Value" "R_6k8_0402" (at 20.32 -12.7 0)
        (effects (font (size 1.27 1.27) (thickness 0.15)) (justify left bottom) hide)
      )
      (property "Footprint" "antmicro-footprints:R_0402_1005Metric" (at 20.32 -15.24 0)
        (effects (font (size 1.27 1.27) (thickness 0.15)) (justify left bottom) hide)
      )
      (property "Datasheet" "https://www.bourns.com/docs/product-datasheets/cr.pdf" (at 20.32 -17.78 0)
        (effects (font (size 1.27 1.27) (thickness 0.15)) (justify left bottom) hide)
      )
      (property "MPN" "CR0402-FX-6801GLF" (at 20.32 -20.32 0)
        (effects (font (size 1.27 1.27) (thickness 0.15)) (justify left bottom) hide)
      )
      (property "Manufacturer" "Bourns" (at 20.32 -22.86 0)
        (effects (font (size 1.27 1.27) (thickness 0.15)) (justify left bottom) hide)
      )
      (property "License" "Apache-2.0" (at 20.32 -25.4 0)
        (effects (font (size 1.27 1.27) (thickness 0.15)) (justify left bottom) hide)
      )
      (property "Author" "Antmicro" (at 20.32 -27.94 0)
        (effects (font (size 1.27 1.27) (thickness 0.15)) (justify left bottom) hide)
      )
      (property "Val" "6k8" (at 20.32 -7.62 0)
        (effects (font (size 1.27 1.27) (thickness 0.15)) (justify left bottom))
      )
      (property "Tolerance" "1%" (at 20.32 -10.16 0)
        (effects (font (size 1.27 1.27)) (justify left bottom) hide)
      )
      (property "ki_keywords" "0402, SMT, RESISTOR, PASSIVE" (at 0 0 0)
        (effects (font (size 1.27 1.27)) hide)
      )
      (property "ki_description" "SMD Chip Resistor, 6.8 kohm, ± 1%, 63 mW, 0402 [1005 Metric], Thick Film, General Purpose" (at 0 0 0)
        (effects (font (size 1.27 1.27)) hide)
      )
      (symbol "R_6k8_0402_0_1"
        (rectangle (start 0.635 0.889) (end 4.445 -0.889)
          (stroke (width 0.254) (type default))
          (fill (type none))
        )
      )
      (symbol "R_6k8_0402_1_1"
        (pin passive line (at 0 0 0) (length 0.635)
          (name "~" (effects (font (size 1.27 1.27))))
          (number "1" (effects (font (size 1.27 1.27))))
        )
        (pin passive line (at 5.08 0 180) (length 0.635)
          (name "~" (effects (font (size 1.27 1.27))))
          (number "2" (effects (font (size 1.27 1.27))))
        )
      )
    )
	(symbol "antmicroResistors0603:R_0R_0603" (pin_numbers hide) (pin_names hide) (in_bom yes) (on_board yes)
      (property "Reference" "R" (at 20.32 -5.08 0)
        (effects (font (size 1.27 1.27) (thickness 0.15)) (justify left bottom))
      )
      (property "Value" "R_0R_0603" (at 20.32 -12.7 0)
        (effects (font (size 1.27 1.27) (thickness 0.15)) (justify left bottom) hide)
      )
      (property "Footprint" "antmicro-footprints:R_0603_1608Metric" (at 20.32 -15.24 0)
        (effects (font (size 1.27 1.27) (thickness 0.15)) (justify left bottom) hide)
      )
      (property "Datasheet" "https://www.bourns.com/docs/product-datasheets/cr.pdf?sfvrsn=574d41f6_14" (at 20.32 -17.78 0)
        (effects (font (size 1.27 1.27) (thickness 0.15)) (justify left bottom) hide)
      )
      (property "MPN" "CR0603-J/-000ELF" (at 20.32 -20.32 0)
        (effects (font (size 1.27 1.27) (thickness 0.15)) (justify left bottom) hide)
      )
      (property "Manufacturer" "Bourns" (at 20.32 -22.86 0)
        (effects (font (size 1.27 1.27) (thickness 0.15)) (justify left bottom) hide)
      )
      (property "License" "Apache-2.0" (at 20.32 -25.4 0)
        (effects (font (size 1.27 1.27) (thickness 0.15)) (justify left bottom) hide)
      )
      (property "Author" "Antmicro" (at 20.32 -27.94 0)
        (effects (font (size 1.27 1.27) (thickness 0.15)) (justify left bottom) hide)
      )
      (property "Val" "0R" (at 20.32 -7.62 0)
        (effects (font (size 1.27 1.27) (thickness 0.15)) (justify left bottom))
      )
      (property "Tolerance" "~" (at 20.32 -10.16 0)
        (effects (font (size 1.27 1.27)) (justify left bottom) hide)
      )
      (property "Current" "1A" (at 20.32 -30.48 0)
        (effects (font (size 1.27 1.27) (thickness 0.15)) (justify left bottom) hide)
      )
      (property "ki_keywords" "0603, SMT, RESISTOR, PASSIVE" (at 0 0 0)
        (effects (font (size 1.27 1.27)) hide)
      )
      (property "ki_description" "Zero Ohm Resistor, Jumper, 0603 [1608 Metric], Thick Film, 100 mW, 1 A, Surface Mount Device, CR" (at 0 0 0)
        (effects (font (size 1.27 1.27)) hide)
      )
      (symbol "R_0R_0603_0_1"
        (rectangle (start 0.635 0.889) (end 4.445 -0.889)
          (stroke (width 0.254) (type default))
          (fill (type none))
        )
      )
      (symbol "R_0R_0603_1_1"
        (pin passive line (at 0 0 0) (length 0.635)
          (name "~" (effects (font (size 1.27 1.27))))
          (number "1" (effects (font (size 1.27 1.27))))
        )
        (pin passive line (at 5.08 0 180) (length 0.635)
          (name "~" (effects (font (size 1.27 1.27))))
          (number "2" (effects (font (size 1.27 1.27))))
        )
      )
    )
	(symbol "antmicroResistors0603:R_1k_0603" (pin_numbers hide) (pin_names hide) (in_bom yes) (on_board yes)
      (property "Reference" "R" (at 20.32 -5.08 0)
        (effects (font (size 1.27 1.27) (thickness 0.15)) (justify left bottom))
      )
      (property "Value" "R_1k_0603" (at 20.32 -12.7 0)
        (effects (font (size 1.27 1.27) (thickness 0.15)) (justify left bottom) hide)
      )
      (property "Footprint" "antmicro-footprints:R_0603_1608Metric" (at 20.32 -15.24 0)
        (effects (font (size 1.27 1.27) (thickness 0.15)) (justify left bottom) hide)
      )
      (property "Datasheet" "https://www.bourns.com/docs/product-datasheets/cr.pdf" (at 20.32 -17.78 0)
        (effects (font (size 1.27 1.27) (thickness 0.15)) (justify left bottom) hide)
      )
      (property "MPN" "CR0603-FX-1001ELF" (at 20.32 -20.32 0)
        (effects (font (size 1.27 1.27) (thickness 0.15)) (justify left bottom) hide)
      )
      (property "Manufacturer" "Bourns" (at 20.32 -22.86 0)
        (effects (font (size 1.27 1.27) (thickness 0.15)) (justify left bottom) hide)
      )
      (property "License" "Apache-2.0" (at 20.32 -25.4 0)
        (effects (font (size 1.27 1.27) (thickness 0.15)) (justify left bottom) hide)
      )
      (property "Author" "Antmicro" (at 20.32 -27.94 0)
        (effects (font (size 1.27 1.27) (thickness 0.15)) (justify left bottom) hide)
      )
      (property "Val" "1k" (at 20.32 -7.62 0)
        (effects (font (size 1.27 1.27) (thickness 0.15)) (justify left bottom))
      )
      (property "Tolerance" "1%" (at 20.32 -10.16 0)
        (effects (font (size 1.27 1.27)) (justify left bottom) hide)
      )
      (property "ki_keywords" "0603, SMT, RESISTOR, PASSIVE" (at 0 0 0)
        (effects (font (size 1.27 1.27)) hide)
      )
      (property "ki_description" "SMD Chip Resistor, 1 kohm, ± 1%, 100 mW, 0603 [1608 Metric], Thick Film, General Purpose" (at 0 0 0)
        (effects (font (size 1.27 1.27)) hide)
      )
      (symbol "R_1k_0603_0_1"
        (rectangle (start 0.635 0.889) (end 4.445 -0.889)
          (stroke (width 0.254) (type default))
          (fill (type none))
        )
      )
      (symbol "R_1k_0603_1_1"
        (pin passive line (at 0 0 0) (length 0.635)
          (name "~" (effects (font (size 1.27 1.27))))
          (number "1" (effects (font (size 1.27 1.27))))
        )
        (pin passive line (at 5.08 0 180) (length 0.635)
          (name "~" (effects (font (size 1.27 1.27))))
          (number "2" (effects (font (size 1.27 1.27))))
        )
      )
    )
	(symbol "antmicroResistors0603:R_2k2_0603" (pin_numbers hide) (pin_names hide) (in_bom yes) (on_board yes)
      (property "Reference" "R" (at 20.32 -5.08 0)
        (effects (font (size 1.27 1.27) (thickness 0.15)) (justify left bottom))
      )
      (property "Value" "R_2k2_0603" (at 20.32 -12.7 0)
        (effects (font (size 1.27 1.27) (thickness 0.15)) (justify left bottom) hide)
      )
      (property "Footprint" "antmicro-footprints:R_0603_1608Metric" (at 20.32 -15.24 0)
        (effects (font (size 1.27 1.27) (thickness 0.15)) (justify left bottom) hide)
      )
      (property "Datasheet" "https://www.bourns.com/docs/product-datasheets/cr.pdf" (at 20.32 -17.78 0)
        (effects (font (size 1.27 1.27) (thickness 0.15)) (justify left bottom) hide)
      )
      (property "MPN" "CR0603-FX-2201ELF" (at 20.32 -20.32 0)
        (effects (font (size 1.27 1.27) (thickness 0.15)) (justify left bottom) hide)
      )
      (property "Manufacturer" "Bourns" (at 20.32 -22.86 0)
        (effects (font (size 1.27 1.27) (thickness 0.15)) (justify left bottom) hide)
      )
      (property "License" "Apache-2.0" (at 20.32 -25.4 0)
        (effects (font (size 1.27 1.27) (thickness 0.15)) (justify left bottom) hide)
      )
      (property "Author" "Antmicro" (at 20.32 -27.94 0)
        (effects (font (size 1.27 1.27) (thickness 0.15)) (justify left bottom) hide)
      )
      (property "Val" "2k2" (at 20.32 -7.62 0)
        (effects (font (size 1.27 1.27) (thickness 0.15)) (justify left bottom))
      )
      (property "Tolerance" "1%" (at 20.32 -10.16 0)
        (effects (font (size 1.27 1.27)) (justify left bottom) hide)
      )
      (property "ki_keywords" "0603, SMT, RESISTOR, PASSIVE" (at 0 0 0)
        (effects (font (size 1.27 1.27)) hide)
      )
      (property "ki_description" "SMD Chip Resistor, 2.2 kohm, ± 1%, 100 mW, 0603 [1608 Metric], Thick Film, General Purpose" (at 0 0 0)
        (effects (font (size 1.27 1.27)) hide)
      )
      (symbol "R_2k2_0603_0_1"
        (rectangle (start 0.635 0.889) (end 4.445 -0.889)
          (stroke (width 0.254) (type default))
          (fill (type none))
        )
      )
      (symbol "R_2k2_0603_1_1"
        (pin passive line (at 0 0 0) (length 0.635)
          (name "~" (effects (font (size 1.27 1.27))))
          (number "1" (effects (font (size 1.27 1.27))))
        )
        (pin passive line (at 5.08 0 180) (length 0.635)
          (name "~" (effects (font (size 1.27 1.27))))
          (number "2" (effects (font (size 1.27 1.27))))
        )
      )
    )
	(symbol "antmicroResistors0603:R_4k7_0603" (pin_numbers hide) (pin_names hide) (in_bom yes) (on_board yes)
      (property "Reference" "R" (at 20.32 -5.08 0)
        (effects (font (size 1.27 1.27) (thickness 0.15)) (justify left bottom))
      )
      (property "Value" "R_4k7_0603" (at 20.32 -12.7 0)
        (effects (font (size 1.27 1.27) (thickness 0.15)) (justify left bottom) hide)
      )
      (property "Footprint" "antmicro-footprints:R_0603_1608Metric" (at 20.32 -15.24 0)
        (effects (font (size 1.27 1.27) (thickness 0.15)) (justify left bottom) hide)
      )
      (property "Datasheet" "https://www.bourns.com/docs/product-datasheets/cr.pdf" (at 20.32 -17.78 0)
        (effects (font (size 1.27 1.27) (thickness 0.15)) (justify left bottom) hide)
      )
      (property "MPN" "CR0603-FX-4701ELF" (at 20.32 -20.32 0)
        (effects (font (size 1.27 1.27) (thickness 0.15)) (justify left bottom) hide)
      )
      (property "Manufacturer" "Bourns" (at 20.32 -22.86 0)
        (effects (font (size 1.27 1.27) (thickness 0.15)) (justify left bottom) hide)
      )
      (property "License" "Apache-2.0" (at 20.32 -25.4 0)
        (effects (font (size 1.27 1.27) (thickness 0.15)) (justify left bottom) hide)
      )
      (property "Author" "Antmicro" (at 20.32 -27.94 0)
        (effects (font (size 1.27 1.27) (thickness 0.15)) (justify left bottom) hide)
      )
      (property "Val" "4k7" (at 20.32 -7.62 0)
        (effects (font (size 1.27 1.27) (thickness 0.15)) (justify left bottom))
      )
      (property "Tolerance" "1%" (at 20.32 -10.16 0)
        (effects (font (size 1.27 1.27)) (justify left bottom) hide)
      )
      (property "ki_keywords" "0603, SMT, RESISTOR, PASSIVE" (at 0 0 0)
        (effects (font (size 1.27 1.27)) hide)
      )
      (property "ki_description" "SMD Chip Resistor, 4.7 kohm, ± 1%, 100 mW, 0603 [1608 Metric], Thick Film, General Purpose" (at 0 0 0)
        (effects (font (size 1.27 1.27)) hide)
      )
      (symbol "R_4k7_0603_0_1"
        (rectangle (start 0.635 0.889) (end 4.445 -0.889)
          (stroke (width 0.254) (type default))
          (fill (type none))
        )
      )
      (symbol "R_4k7_0603_1_1"
        (pin passive line (at 0 0 0) (length 0.635)
          (name "~" (effects (font (size 1.27 1.27))))
          (number "1" (effects (font (size 1.27 1.27))))
        )
        (pin passive line (at 5.08 0 180) (length 0.635)
          (name "~" (effects (font (size 1.27 1.27))))
          (number "2" (effects (font (size 1.27 1.27))))
        )
      )
    )
	(symbol "antmicroResonators:Resonator_12MHz_KX-7" (pin_names hide) (in_bom yes) (on_board yes)
      (property "Reference" "Y" (at 15.24 -5.08 0)
        (effects (font (size 1.27 1.27) (thickness 0.15)) (justify left bottom))
      )
      (property "Value" "Resonator_12MHz_KX_7" (at 15.24 -12.7 0)
        (effects (font (size 1.27 1.27) (thickness 0.15)) (justify left bottom) hide)
      )
      (property "Footprint" "antmicro-footprints:Resonator_SMD_Geyer_KX-7_3.2x2.5x0.8mm" (at 15.24 -15.24 0)
        (effects (font (size 1.27 1.27) (thickness 0.15)) (justify left bottom) hide)
      )
      (property "Datasheet" "https://media.distrelec.com/Web/Downloads/86/62/KX-7-12-88662.pdf" (at 15.24 -17.78 0)
        (effects (font (size 1.27 1.27) (thickness 0.15)) (justify left bottom) hide)
      )
      (property "MPN" "KX-7_SMD_CRYSTAL_12,0 MHZ" (at 15.24 -7.62 0)
        (effects (font (size 1.27 1.27) (thickness 0.15)) (justify left bottom))
      )
      (property "Manufacturer" "Geyer Electronic" (at 15.24 -20.32 0)
        (effects (font (size 1.27 1.27) (thickness 0.15)) (justify left bottom) hide)
      )
      (property "Author" "Antmicro" (at 15.24 -22.86 0)
        (effects (font (size 1.27 1.27) (thickness 0.15)) (justify left bottom) hide)
      )
      (property "License" "Apache-2.0" (at 15.24 -25.4 0)
        (effects (font (size 1.27 1.27) (thickness 0.15)) (justify left bottom) hide)
      )
      (property "Val" "12 MHz" (at 15.24 -10.16 0)
        (effects (font (size 1.27 1.27) (thickness 0.15)) (justify left bottom))
      )
      (property "ki_keywords" "SMT, CERAMIC, OSCILLATOR" (at 0 0 0)
        (effects (font (size 1.27 1.27)) hide)
      )
      (property "ki_description" "Crystal, 12 MHz, SMT, 3.2mm x 2.5mm, 30 ppm, 12 pF, KX-7" (at 0 0 0)
        (effects (font (size 1.27 1.27)) hide)
      )
      (symbol "Resonator_12MHz_KX-7_1_1"
        (polyline
          (pts
            (xy 2.54 1.27)
            (xy 2.54 -1.27)
          )
          (stroke (width 0.254) (type default))
          (fill (type background))
        )
        (polyline
          (pts
            (xy 5.08 1.27)
            (xy 5.08 -1.27)
          )
          (stroke (width 0.254) (type default))
          (fill (type background))
        )
        (polyline
          (pts
            (xy 1.905 -1.905)
            (xy 1.905 -2.54)
            (xy 5.715 -2.54)
            (xy 5.715 -1.905)
          )
          (stroke (width 0.254) (type default))
          (fill (type none))
        )
        (polyline
          (pts
            (xy 1.905 1.905)
            (xy 1.905 2.54)
            (xy 5.715 2.54)
            (xy 5.715 1.905)
          )
          (stroke (width 0.254) (type default))
          (fill (type none))
        )
        (rectangle (start 3.175 1.905) (end 4.445 -1.905)
          (stroke (width 0.254) (type default))
          (fill (type background))
        )
        (pin passive line (at 0 0 0) (length 2.54)
          (name "~" (effects (font (size 1.27 1.27))))
          (number "1" (effects (font (size 1.27 1.27))))
        )
        (pin passive line (at 3.81 -5.08 90) (length 2.54)
          (name "SH" (effects (font (size 1.27 1.27))))
          (number "2" (effects (font (size 1.27 1.27))))
        )
        (pin passive line (at 7.62 0 180) (length 2.54)
          (name "~" (effects (font (size 1.27 1.27))))
          (number "3" (effects (font (size 1.27 1.27))))
        )
        (pin passive line (at 3.81 -5.08 90) (length 2.54) hide
          (name "SH" (effects (font (size 1.27 1.27))))
          (number "4" (effects (font (size 1.27 1.27))))
        )
      )
    )
	(symbol "antmicroSlideSwitches:SW_SPDT_PCM12SMTR" (in_bom yes) (on_board yes)
      (property "Reference" "SW" (at 27.94 -5.08 0)
        (effects (font (size 1.27 1.27) (thickness 0.15)) (justify left bottom))
      )
      (property "Value" "SW_SPDT_PCM12SMTR" (at 27.94 -7.62 0)
        (effects (font (size 1.27 1.27) (thickness 0.15)) (justify left bottom))
      )
      (property "Footprint" "antmicro-footprints:PCM12SMTR" (at 27.94 -10.16 0)
        (effects (font (size 1.27 1.27) (thickness 0.15)) (justify left bottom) hide)
      )
      (property "Datasheet" "https://www.mouser.com/datasheet/2/60/pcm-1841544.pdf" (at 27.94 -12.7 0)
        (effects (font (size 1.27 1.27) (thickness 0.15)) (justify left bottom) hide)
      )
      (property "Manufacturer" "C&K" (at 27.94 -15.24 0)
        (effects (font (size 1.27 1.27) (thickness 0.15)) (justify left bottom) hide)
      )
      (property "MPN" "PCM12SMTR" (at 27.94 -17.78 0)
        (effects (font (size 1.27 1.27) (thickness 0.15)) (justify left bottom) hide)
      )
      (property "Author" "Antmicro" (at 27.94 -20.32 0)
        (effects (font (size 1.27 1.27) (thickness 0.15)) (justify left bottom) hide)
      )
      (property "License" "Apache-2.0" (at 27.94 -22.86 0)
        (effects (font (size 1.27 1.27) (thickness 0.15)) (justify left bottom) hide)
      )
      (property "ki_keywords" "VERTICAL, SMT, SWITCH, SWITCH, SLIDE" (at 0 0 0)
        (effects (font (size 1.27 1.27)) hide)
      )
      (property "ki_description" "Slide switch" (at 0 0 0)
        (effects (font (size 1.27 1.27)) hide)
      )
      (symbol "SW_SPDT_PCM12SMTR_1_1"
        (polyline
          (pts
            (xy 3.81 0)
            (xy 2.54 0)
          )
          (stroke (width 0.254) (type default))
          (fill (type none))
        )
        (polyline
          (pts
            (xy 4.318 0)
            (xy 8.89 -2.54)
          )
          (stroke (width 0.254) (type default))
          (fill (type none))
        )
        (polyline
          (pts
            (xy 10.16 -2.54)
            (xy 8.89 -2.54)
          )
          (stroke (width 0.254) (type default))
          (fill (type none))
        )
        (polyline
          (pts
            (xy 10.16 2.54)
            (xy 8.89 2.54)
          )
          (stroke (width 0.254) (type default))
          (fill (type none))
        )
        (rectangle (start 2.54 3.81) (end 10.16 -3.81)
          (stroke (width 0.254) (type default))
          (fill (type background))
        )
        (circle (center 4.064 0) (radius 0.3556)
          (stroke (width 0.254) (type default))
          (fill (type outline))
        )
        (circle (center 8.636 -2.54) (radius 0.3556)
          (stroke (width 0.254) (type default))
          (fill (type outline))
        )
        (circle (center 8.89 2.54) (radius 0.3556)
          (stroke (width 0.254) (type default))
          (fill (type outline))
        )
        (pin passive line (at 12.7 2.54 180) (length 2.54)
          (name "~" (effects (font (size 1.27 1.27))))
          (number "1" (effects (font (size 1.27 1.27))))
        )
        (pin passive line (at 0 0 0) (length 2.54)
          (name "~" (effects (font (size 1.27 1.27))))
          (number "2" (effects (font (size 1.27 1.27))))
        )
        (pin passive line (at 12.7 -2.54 180) (length 2.54)
          (name "~" (effects (font (size 1.27 1.27))))
          (number "3" (effects (font (size 1.27 1.27))))
        )
        (pin passive line (at 0 -2.54 0) (length 2.54) hide
          (name "SH" (effects (font (size 1.27 1.27))))
          (number "S1" (effects (font (size 1.27 1.27))))
        )
        (pin passive line (at 0 -2.54 0) (length 2.54) hide
          (name "SH" (effects (font (size 1.27 1.27))))
          (number "S2" (effects (font (size 1.27 1.27))))
        )
        (pin passive line (at 0 -2.54 0) (length 2.54) hide
          (name "SH" (effects (font (size 1.27 1.27))))
          (number "S3" (effects (font (size 1.27 1.27))))
        )
        (pin passive line (at 0 -2.54 0) (length 2.54)
          (name "SH" (effects (font (size 1.27 1.27))))
          (number "S4" (effects (font (size 1.27 1.27))))
        )
      )
    )
	(symbol "antmicroTVSDiodes:PESD5V0S2BQA" (in_bom yes) (on_board yes)
      (property "Reference" "D" (at 27.94 -2.54 0)
        (effects (font (size 1.27 1.27) (thickness 0.15)) (justify left bottom))
      )
      (property "Value" "PESD5V0S2BQA" (at 27.94 -10.16 0)
        (effects (font (size 1.27 1.27) (thickness 0.15)) (justify left bottom) hide)
      )
      (property "Footprint" "antmicro-footprints:TPD2E009DRTR" (at 27.94 -12.7 0)
        (effects (font (size 1.27 1.27) (thickness 0.15)) (justify left bottom) hide)
      )
      (property "Datasheet" "https://4donline.ihs.com/images/VipMasterIC/IC/NEXP/NEXP-S-A0003105620/NEXP-S-A0003107857-1.pdf?hkey=6D3A4C79FDBF58556ACFDE234799DDF0" (at 27.94 -15.24 0)
        (effects (font (size 1.27 1.27) (thickness 0.15)) (justify left bottom) hide)
      )
      (property "MPN" "PESD5V0S2BQA" (at 27.94 -5.08 0)
        (effects (font (size 1.27 1.27) (thickness 0.15)) (justify left bottom))
      )
      (property "Manufacturer" "Nexperia" (at 27.94 -7.62 0)
        (effects (font (size 1.27 1.27) (thickness 0.15)) (justify left bottom) hide)
      )
      (property "Author" "Antmicro" (at 27.94 -17.78 0)
        (effects (font (size 1.27 1.27) (thickness 0.15)) (justify left bottom) hide)
      )
      (property "License" "Apache-2.0" (at 27.94 -20.32 0)
        (effects (font (size 1.27 1.27) (thickness 0.15)) (justify left bottom) hide)
      )
      (property "ki_keywords" "SMT, DIODE, SEMICONDUCTOR, TVS, ESD" (at 0 0 0)
        (effects (font (size 1.27 1.27)) hide)
      )
      (property "ki_description" "TVS diode array, 30 kV, SOT-1215, 5V, 45 pF" (at 0 0 0)
        (effects (font (size 1.27 1.27)) hide)
      )
      (symbol "PESD5V0S2BQA_1_1"
        (polyline
          (pts
            (xy 10.414 -0.254)
            (xy 10.414 -5.842)
          )
          (stroke (width 0.254) (type default))
          (fill (type none))
        )
        (polyline
          (pts
            (xy 9.652 -2.54)
            (xy 11.176 -2.54)
            (xy 11.176 -2.794)
          )
          (stroke (width 0.254) (type default))
          (fill (type none))
        )
        (polyline
          (pts
            (xy 11.43 -4.064)
            (xy 10.414 -2.54)
            (xy 9.398 -4.064)
            (xy 11.43 -4.064)
          )
          (stroke (width 0.254) (type default))
          (fill (type none))
        )
        (rectangle (start 12.7 -7.62) (end 2.54 2.54)
          (stroke (width 0.254) (type default))
          (fill (type background))
        )
        (pin passive line (at 0 0 0) (length 2.54)
          (name "IO1" (effects (font (size 1.27 1.27))))
          (number "1" (effects (font (size 1.27 1.27))))
        )
        (pin passive line (at 0 -2.54 0) (length 2.54)
          (name "IO2" (effects (font (size 1.27 1.27))))
          (number "2" (effects (font (size 1.27 1.27))))
        )
        (pin passive line (at 0 -5.08 0) (length 2.54)
          (name "GND" (effects (font (size 1.27 1.27))))
          (number "3" (effects (font (size 1.27 1.27))))
        )
      )
    )
	(symbol "antmicroTestPoints:TP_1mm_SMD" (pin_names hide) (in_bom no) (on_board yes)
      (property "Reference" "TP" (at 15.24 -5.08 0)
        (effects (font (size 1.27 1.27) (thickness 0.15)) (justify left bottom))
      )
      (property "Value" "TP_1mm_SMD" (at 15.24 -7.62 0)
        (effects (font (size 1.27 1.27) (thickness 0.15)) (justify left bottom) hide)
      )
      (property "Footprint" "antmicro-footprints:TP_SMD_1mm" (at 15.24 -10.16 0)
        (effects (font (size 1.27 1.27) (thickness 0.15)) (justify left bottom) hide)
      )
      (property "Datasheet" "" (at 17.78 -12.7 0)
        (effects (font (size 1.27 1.27) (thickness 0.15)) (justify left bottom) hide)
      )
      (property "MPN" "" (at 0 0 0)
        (effects (font (size 1.27 1.27)) hide)
      )
      (property "Manufacturer" "" (at 0 0 0)
        (effects (font (size 1.27 1.27)) hide)
      )
      (property "Author" "Antmicro" (at 15.24 -15.24 0)
        (effects (font (size 1.27 1.27) (thickness 0.15)) (justify left bottom) hide)
      )
      (property "License" "Apache-2.0" (at 15.24 -17.78 0)
        (effects (font (size 1.27 1.27) (thickness 0.15)) (justify left bottom) hide)
      )
      (property "ki_keywords" "TESTPOINT" (at 0 0 0)
        (effects (font (size 1.27 1.27)) hide)
      )
      (property "ki_description" "Test point 1mm SMD" (at 0 0 0)
        (effects (font (size 1.27 1.27)) hide)
      )
      (symbol "TP_1mm_SMD_1_1"
        (circle (center 3.175 0) (radius 0.635)
          (stroke (width 0.254) (type default))
          (fill (type none))
        )
        (pin passive line (at 0 0 0) (length 2.54)
          (name "1" (effects (font (size 1.27 1.27))))
          (number "1" (effects (font (size 1.27 1.27))))
        )
      )
    )
	(symbol "antmicroTransistorsBipolarSingle:BC856,215" (in_bom yes) (on_board yes)
      (property "Reference" "Q" (at 17.018 2.794 0)
        (effects (font (size 1.27 1.27) (thickness 0.15)) (justify left bottom))
      )
      (property "Value" "BC856,215" (at 17.018 0.254 0)
        (effects (font (size 1.27 1.27) (thickness 0.15)) (justify left bottom) hide)
      )
      (property "Footprint" "antmicro-footprints:SOT-23-3" (at 17.018 -2.286 0)
        (effects (font (size 1.27 1.27) (thickness 0.15)) (justify left bottom) hide)
      )
      (property "Datasheet" "https://eu.mouser.com/datasheet/2/916/BC856_BC857_BC858-1318701.pdf" (at 17.018 -4.826 0)
        (effects (font (size 1.27 1.27) (thickness 0.15)) (justify left bottom) hide)
      )
      (property "MPN" "BC856,215" (at 17.018 -7.366 0)
        (effects (font (size 1.27 1.27) (thickness 0.15)) (justify left bottom))
      )
      (property "Manufacturer" "Nexperia" (at 17.018 -9.906 0)
        (effects (font (size 1.27 1.27) (thickness 0.15)) (justify left bottom) hide)
      )
      (property "Author" "Antmicro" (at 17.018 -12.446 0)
        (effects (font (size 1.27 1.27) (thickness 0.15)) (justify left bottom) hide)
      )
      (property "License" "Apache-2.0" (at 17.018 -14.986 0)
        (effects (font (size 1.27 1.27) (thickness 0.15)) (justify left bottom) hide)
      )
      (property "ki_keywords" "SMT, TRANSISTOR, SEMICONDUCTOR, PNP" (at 0 0 0)
        (effects (font (size 1.27 1.27)) hide)
      )
      (property "ki_description" "Bipolar (BJT) Single Transistor, PNP, 65 V, 100 mA, 250 mW, SOT-23-3, Surface Mount" (at 0 0 0)
        (effects (font (size 1.27 1.27)) hide)
      )
      (symbol "BC856,215_1_1"
        (polyline
          (pts
            (xy 2.54 0)
            (xy 4.318 0)
          )
          (stroke (width 0.25) (type default))
          (fill (type none))
        )
        (polyline
          (pts
            (xy 4.445 0.635)
            (xy 6.35 2.54)
          )
          (stroke (width 0.254) (type default))
          (fill (type background))
        )
        (polyline
          (pts
            (xy 4.445 -0.635)
            (xy 6.35 -2.54)
            (xy 6.35 -2.54)
          )
          (stroke (width 0.254) (type default))
          (fill (type background))
        )
        (polyline
          (pts
            (xy 4.445 1.905)
            (xy 4.445 -1.905)
            (xy 4.445 -1.905)
          )
          (stroke (width 0.254) (type default))
          (fill (type background))
        )
        (polyline
          (pts
            (xy 5.08 -1.778)
            (xy 5.588 -1.27)
            (xy 4.572 -0.762)
            (xy 5.08 -1.778)
            (xy 5.08 -1.778)
          )
          (stroke (width 0.254) (type default))
          (fill (type outline))
        )
        (circle (center 5.3848 0) (radius 2.8194)
          (stroke (width 0.254) (type default))
          (fill (type background))
        )
        (pin input line (at 0 0 0) (length 2.54)
          (name "~" (effects (font (size 1.27 1.27))))
          (number "1" (effects (font (size 1.27 1.27))))
        )
        (pin passive line (at 6.35 -5.08 90) (length 2.54)
          (name "~" (effects (font (size 1.27 1.27))))
          (number "2" (effects (font (size 1.27 1.27))))
        )
        (pin passive line (at 6.35 5.08 270) (length 2.54)
          (name "~" (effects (font (size 1.27 1.27))))
          (number "3" (effects (font (size 1.27 1.27))))
        )
      )
    )
	(symbol "antmicroTransistorsFETsMOSFETsSingle:2N7002_SOT-23-3" (pin_names (offset 0)) (in_bom yes) (on_board yes)
      (property "Reference" "Q" (at 22.86 -5.08 0)
        (effects (font (size 1.27 1.27) (thickness 0.15)) (justify left bottom))
      )
      (property "Value" "2N7002_SOT-23-3" (at 22.86 -7.62 0)
        (effects (font (size 1.27 1.27) (thickness 0.15)) (justify left bottom) hide)
      )
      (property "Footprint" "antmicro-footprints:SOT-23-3" (at 22.86 -10.16 0)
        (effects (font (size 1.27 1.27) (thickness 0.15)) (justify left bottom) hide)
      )
      (property "Datasheet" "https://www.onsemi.com/pub/Collateral/NDS7002A-D.PDF" (at 22.86 -12.7 0)
        (effects (font (size 1.27 1.27) (thickness 0.15)) (justify left bottom) hide)
      )
      (property "MPN" "2N7002" (at 22.86 -15.24 0)
        (effects (font (size 1.27 1.27) (thickness 0.15)) (justify left bottom))
      )
      (property "Manufacturer" "ON Semiconductor" (at 22.86 -17.78 0)
        (effects (font (size 1.27 1.27) (thickness 0.15)) (justify left bottom) hide)
      )
      (property "Author" "Antmicro" (at 22.86 -20.32 0)
        (effects (font (size 1.27 1.27) (thickness 0.15)) (justify left bottom) hide)
      )
      (property "License" "Apache-2.0" (at 22.86 -22.86 0)
        (effects (font (size 1.27 1.27) (thickness 0.15)) (justify left bottom) hide)
      )
      (property "ki_keywords" "SMT, TRANSISTOR, SEMICONDUCTOR, NMOS" (at 0 0 0)
        (effects (font (size 1.27 1.27)) hide)
      )
      (property "ki_description" "Power MOSFET, N Channel, 60 V, 115 mA, 1.2 ohm, SOT-23, Surface Mount" (at 0 0 0)
        (effects (font (size 1.27 1.27)) hide)
      )
      (symbol "2N7002_SOT-23-3_1_1"
        (polyline
          (pts
            (xy 5.08 1.143)
            (xy 5.08 0.635)
          )
          (stroke (width 0.254) (type default))
          (fill (type background))
        )
        (polyline
          (pts
            (xy 5.08 1.143)
            (xy 5.08 1.651)
          )
          (stroke (width 0.254) (type default))
          (fill (type background))
        )
        (polyline
          (pts
            (xy 5.08 2.54)
            (xy 5.08 2.032)
          )
          (stroke (width 0.254) (type default))
          (fill (type background))
        )
        (polyline
          (pts
            (xy 5.08 2.54)
            (xy 5.08 3.048)
          )
          (stroke (width 0.254) (type default))
          (fill (type background))
        )
        (polyline
          (pts
            (xy 5.08 4.445)
            (xy 5.08 3.429)
          )
          (stroke (width 0.254) (type default))
          (fill (type background))
        )
        (polyline
          (pts
            (xy 7.62 1.143)
            (xy 5.08 1.143)
          )
          (stroke (width 0.254) (type default))
          (fill (type background))
        )
        (polyline
          (pts
            (xy 9.144 3.048)
            (xy 8.128 3.048)
          )
          (stroke (width 0.254) (type default))
          (fill (type background))
        )
        (polyline
          (pts
            (xy 2.54 0)
            (xy 4.572 0)
            (xy 4.572 3.937)
          )
          (stroke (width 0.254) (type default))
          (fill (type none))
        )
        (polyline
          (pts
            (xy 7.62 -1.27)
            (xy 7.62 2.54)
            (xy 5.08 2.54)
          )
          (stroke (width 0.254) (type default))
          (fill (type none))
        )
        (polyline
          (pts
            (xy 7.62 6.35)
            (xy 7.62 3.937)
            (xy 5.08 3.937)
          )
          (stroke (width 0.254) (type default))
          (fill (type none))
        )
        (polyline
          (pts
            (xy 5.08 2.54)
            (xy 5.842 3.048)
            (xy 5.842 2.032)
            (xy 5.08 2.54)
          )
          (stroke (width 0.254) (type default))
          (fill (type outline))
        )
        (polyline
          (pts
            (xy 8.636 3.048)
            (xy 8.128 2.286)
            (xy 9.144 2.286)
            (xy 8.636 3.048)
          )
          (stroke (width 0.254) (type default))
          (fill (type outline))
        )
        (polyline
          (pts
            (xy 7.493 0.635)
            (xy 8.636 0.635)
            (xy 8.636 3.937)
            (xy 8.636 4.445)
            (xy 7.493 4.445)
          )
          (stroke (width 0.254) (type default))
          (fill (type background))
        )
        (circle (center 6.35 2.54) (radius 3.302)
          (stroke (width 0.254) (type default))
          (fill (type background))
        )
        (circle (center 7.62 0.635) (radius 0.127)
          (stroke (width 0.254) (type default))
          (fill (type background))
        )
        (circle (center 7.62 1.143) (radius 0.127)
          (stroke (width 0.254) (type default))
          (fill (type background))
        )
        (circle (center 7.62 4.445) (radius 0.127)
          (stroke (width 0.254) (type default))
          (fill (type background))
        )
        (pin passive line (at 0 0 0) (length 2.54)
          (name "G" (effects (font (size 1.27 1.27))))
          (number "1" (effects (font (size 1.27 1.27))))
        )
        (pin passive line (at 7.62 -3.81 90) (length 2.54)
          (name "S" (effects (font (size 1.27 1.27))))
          (number "2" (effects (font (size 1.27 1.27))))
        )
        (pin passive line (at 7.62 8.89 270) (length 2.54)
          (name "D" (effects (font (size 1.27 1.27))))
          (number "3" (effects (font (size 1.27 1.27))))
        )
      )
    )
	(symbol "antmicroUSBConnectors:USB-C_GCT_USB4145-03-0070-C" (in_bom yes) (on_board yes)
      (property "Reference" "J" (at 21.59 -2.54 0)
        (effects (font (size 1.27 1.27) (thickness 0.15)) (justify left bottom))
      )
      (property "Value" "USB-C_GCT_USB4145-03-0070-C" (at 21.59 -7.62 0)
        (effects (font (size 1.27 1.27) (thickness 0.15)) (justify left bottom) hide)
      )
      (property "Footprint" "antmicro-footprints:USB-C_Receptacle_GCT_USB4145-03-0070-C" (at 21.59 -10.16 0)
        (effects (font (size 1.27 1.27) (thickness 0.15)) (justify left bottom) hide)
      )
      (property "Datasheet" "https://gct.co/files/drawings/usb4145.pdf" (at 21.59 -12.7 0)
        (effects (font (size 1.27 1.27) (thickness 0.15)) (justify left bottom) hide)
      )
      (property "MPN" "USB4145-03-0070-C" (at 21.59 -5.08 0)
        (effects (font (size 1.27 1.27) (thickness 0.15)) (justify left bottom))
      )
      (property "Manufacturer" "GCT" (at 21.59 -15.24 0)
        (effects (font (size 1.27 1.27) (thickness 0.15)) (justify left bottom) hide)
      )
      (property "License" "Apache-2.0" (at 21.59 -17.78 0)
        (effects (font (size 1.27 1.27) (thickness 0.15)) (justify left bottom) hide)
      )
      (property "Author" "Antmicro" (at 21.59 -20.32 0)
        (effects (font (size 1.27 1.27) (thickness 0.15)) (justify left bottom) hide)
      )
      (property "ki_keywords" "USB, CONNECTOR, SMT, VERTICAL" (at 0 0 0)
        (effects (font (size 1.27 1.27)) hide)
      )
      (property "ki_description" "USB-C (USB TYPE-C) USB 2.0 Receptacle Connector 24 (16+8 Dummy) Postion  Surface Mount, Vertical" (at 0 0 0)
        (effects (font (size 1.27 1.27)) hide)
      )
      (symbol "USB-C_GCT_USB4145-03-0070-C_1_1"
        (rectangle (start -22.86 2.54) (end -3.81 -38.1)
          (stroke (width 0.254) (type default))
          (fill (type background))
        )
        (circle (center -20.066 -18.034) (radius 0.284)
          (stroke (width 0.254) (type default))
          (fill (type outline))
        )
        (circle (center -19.177 -20.828) (radius 0.5236)
          (stroke (width 0.254) (type default))
          (fill (type outline))
        )
        (rectangle (start -18.669 -18.034) (end -17.907 -17.272)
          (stroke (width 0.254) (type default))
          (fill (type outline))
        )
        (arc (start -16.51 -21.59) (mid -14.605 -23.4867) (end -12.7 -21.59)
          (stroke (width 0.254) (type default))
          (fill (type background))
        )
        (arc (start -15.24 -21.59) (mid -14.605 -22.2223) (end -13.97 -21.59)
          (stroke (width 0.254) (type default))
          (fill (type outline))
        )
        (arc (start -15.24 -21.59) (mid -14.605 -22.2223) (end -13.97 -21.59)
          (stroke (width 0.254) (type default))
          (fill (type background))
        )
        (rectangle (start -15.24 -21.59) (end -13.97 -13.97)
          (stroke (width 0.254) (type default))
          (fill (type outline))
        )
        (arc (start -13.97 -13.97) (mid -14.605 -13.3377) (end -15.24 -13.97)
          (stroke (width 0.254) (type default))
          (fill (type outline))
        )
        (arc (start -13.97 -13.97) (mid -14.605 -13.3377) (end -15.24 -13.97)
          (stroke (width 0.254) (type default))
          (fill (type background))
        )
        (arc (start -12.7 -13.97) (mid -14.605 -12.0733) (end -16.51 -13.97)
          (stroke (width 0.254) (type default))
          (fill (type background))
        )
        (polyline
          (pts
            (xy -19.177 -20.701)
            (xy -19.177 -16.383)
          )
          (stroke (width 0.254) (type default))
          (fill (type background))
        )
        (polyline
          (pts
            (xy -16.51 -21.59)
            (xy -16.51 -13.97)
          )
          (stroke (width 0.254) (type default))
          (fill (type background))
        )
        (polyline
          (pts
            (xy -12.7 -13.97)
            (xy -12.7 -21.59)
          )
          (stroke (width 0.254) (type default))
          (fill (type background))
        )
        (polyline
          (pts
            (xy -19.177 -19.939)
            (xy -20.066 -19.05)
            (xy -20.066 -18.415)
          )
          (stroke (width 0.254) (type default))
          (fill (type background))
        )
        (polyline
          (pts
            (xy -19.177 -19.558)
            (xy -18.288 -18.669)
            (xy -18.288 -18.034)
          )
          (stroke (width 0.254) (type default))
          (fill (type background))
        )
        (polyline
          (pts
            (xy -19.812 -16.383)
            (xy -19.177 -15.24)
            (xy -18.542 -16.383)
            (xy -19.812 -16.383)
          )
          (stroke (width 0.254) (type default))
          (fill (type outline))
        )
        (pin power_in line (at 0 -33.02 180) (length 3.81)
          (name "GND" (effects (font (size 1.27 1.27))))
          (number "A1" (effects (font (size 1.27 1.27))))
        )
        (pin passive line (at 0 -33.02 180) (length 3.81) hide
          (name "GND" (effects (font (size 1.27 1.27))))
          (number "A12" (effects (font (size 1.27 1.27))))
        )
        (pin passive line (at 0 0 180) (length 3.81)
          (name "VBUS" (effects (font (size 1.27 1.27))))
          (number "A4" (effects (font (size 1.27 1.27))))
        )
        (pin bidirectional line (at 0 -5.08 180) (length 3.81)
          (name "CC_{1}" (effects (font (size 1.27 1.27))))
          (number "A5" (effects (font (size 1.27 1.27))))
        )
        (pin bidirectional line (at 0 -12.7 180) (length 3.81)
          (name "D_{A}+" (effects (font (size 1.27 1.27))))
          (number "A6" (effects (font (size 1.27 1.27))))
        )
        (pin bidirectional line (at 0 -15.24 180) (length 3.81)
          (name "D_{A}-" (effects (font (size 1.27 1.27))))
          (number "A7" (effects (font (size 1.27 1.27))))
        )
        (pin bidirectional line (at 0 -25.4 180) (length 3.81)
          (name "SBU_{1}" (effects (font (size 1.27 1.27))))
          (number "A8" (effects (font (size 1.27 1.27))))
        )
        (pin passive line (at 0 0 180) (length 3.81) hide
          (name "VBUS" (effects (font (size 1.27 1.27))))
          (number "A9" (effects (font (size 1.27 1.27))))
        )
        (pin passive line (at 0 -33.02 180) (length 3.81) hide
          (name "GND" (effects (font (size 1.27 1.27))))
          (number "B1" (effects (font (size 1.27 1.27))))
        )
        (pin passive line (at 0 -33.02 180) (length 3.81) hide
          (name "GND" (effects (font (size 1.27 1.27))))
          (number "B12" (effects (font (size 1.27 1.27))))
        )
        (pin passive line (at 0 0 180) (length 3.81) hide
          (name "VBUS" (effects (font (size 1.27 1.27))))
          (number "B4" (effects (font (size 1.27 1.27))))
        )
        (pin bidirectional line (at 0 -7.62 180) (length 3.81)
          (name "CC_{2}" (effects (font (size 1.27 1.27))))
          (number "B5" (effects (font (size 1.27 1.27))))
        )
        (pin bidirectional line (at 0 -17.78 180) (length 3.81)
          (name "D_{B}+" (effects (font (size 1.27 1.27))))
          (number "B6" (effects (font (size 1.27 1.27))))
        )
        (pin bidirectional line (at 0 -20.32 180) (length 3.81)
          (name "D_{B}-" (effects (font (size 1.27 1.27))))
          (number "B7" (effects (font (size 1.27 1.27))))
        )
        (pin bidirectional line (at 0 -27.94 180) (length 3.81)
          (name "SBU_{2}" (effects (font (size 1.27 1.27))))
          (number "B8" (effects (font (size 1.27 1.27))))
        )
        (pin passive line (at 0 0 180) (length 3.81) hide
          (name "VBUS" (effects (font (size 1.27 1.27))))
          (number "B9" (effects (font (size 1.27 1.27))))
        )
        (pin passive line (at 0 -35.56 180) (length 3.81)
          (name "SH" (effects (font (size 1.27 1.27))))
          (number "SH" (effects (font (size 1.27 1.27))))
        )
      )
    )
	(symbol "antmicroWire2BoardConnectors:JST_SH_1x4_BM04B-SRSS-TB-LF-SN" (in_bom yes) (on_board yes)
      (property "Reference" "J" (at 20.32 -5.08 0)
        (effects (font (size 1.27 1.27) (thickness 0.15)) (justify left bottom))
      )
      (property "Value" "JST_SH_1x4_BM04B-SRSS-TB-LF-SN" (at 20.32 -7.62 0)
        (effects (font (size 1.27 1.27) (thickness 0.15)) (justify left bottom) hide)
      )
      (property "Footprint" "antmicro-footprints:Conn_JST_SH_1x4_BM04B-SRSS-TB-LF-SN" (at 20.32 -10.16 0)
        (effects (font (size 1.27 1.27) (thickness 0.15)) (justify left bottom) hide)
      )
      (property "Datasheet" "https://www.jst-mfg.com/product/pdf/eng/eSH.pdf" (at 20.32 -12.7 0)
        (effects (font (size 1.27 1.27) (thickness 0.15)) (justify left bottom) hide)
      )
      (property "MPN" "BM04B-SRSS-TB(LF)(SN) " (at 20.32 -15.24 0)
        (effects (font (size 1.27 1.27) (thickness 0.15)) (justify left bottom))
      )
      (property "Manufacturer" "JST Automotive Connectors" (at 20.32 -17.78 0)
        (effects (font (size 1.27 1.27) (thickness 0.15)) (justify left bottom) hide)
      )
      (property "Author" "Antmicro" (at 20.32 -20.32 0)
        (effects (font (size 1.27 1.27) (thickness 0.15)) (justify left bottom) hide)
      )
      (property "License" "Apache-2.0" (at 20.32 -22.86 0)
        (effects (font (size 1.27 1.27) (thickness 0.15)) (justify left bottom) hide)
      )
      (property "ki_keywords" "VERTICAL, SMT, WIRE-BOARD, CONNECTOR" (at 0 0 0)
        (effects (font (size 1.27 1.27)) hide)
      )
      (property "ki_description" "Pin Header, Top Entry, Wire-to-Board, 1 mm, 1 Rows, 4 Contacts, Surface Mount, SR" (at 0 0 0)
        (effects (font (size 1.27 1.27)) hide)
      )
      (symbol "JST_SH_1x4_BM04B-SRSS-TB-LF-SN_1_1"
        (rectangle (start 2.54 -10.033) (end 3.81 -10.287)
          (stroke (width 0.254) (type default))
          (fill (type background))
        )
        (rectangle (start 2.54 -7.493) (end 3.81 -7.747)
          (stroke (width 0.254) (type default))
          (fill (type background))
        )
        (rectangle (start 2.54 -4.953) (end 3.81 -5.207)
          (stroke (width 0.254) (type default))
          (fill (type background))
        )
        (rectangle (start 2.54 -2.413) (end 3.81 -2.667)
          (stroke (width 0.254) (type default))
          (fill (type background))
        )
        (rectangle (start 2.54 0.127) (end 3.81 -0.127)
          (stroke (width 0.254) (type default))
          (fill (type background))
        )
        (rectangle (start 2.54 2.54) (end 5.08 -12.7)
          (stroke (width 0.254) (type default))
          (fill (type background))
        )
        (pin passive line (at 0 0 0) (length 2.54)
          (name "~" (effects (font (size 1.27 1.27))))
          (number "1" (effects (font (size 1.27 1.27))))
        )
        (pin passive line (at 0 -2.54 0) (length 2.54)
          (name "~" (effects (font (size 1.27 1.27))))
          (number "2" (effects (font (size 1.27 1.27))))
        )
        (pin passive line (at 0 -5.08 0) (length 2.54)
          (name "~" (effects (font (size 1.27 1.27))))
          (number "3" (effects (font (size 1.27 1.27))))
        )
        (pin passive line (at 0 -7.62 0) (length 2.54)
          (name "~" (effects (font (size 1.27 1.27))))
          (number "4" (effects (font (size 1.27 1.27))))
        )
        (pin passive line (at 0 -10.16 0) (length 2.54)
          (name "~" (effects (font (size 1.27 1.27))))
          (number "MP" (effects (font (size 1.27 1.27))))
        )
      )
    )
	(symbol "antmicroWire2BoardConnectors:Molex_KK_1x4_22-27-2041" (in_bom yes) (on_board yes)
      (property "Reference" "J" (at 13.335 -2.54 0)
        (effects (font (size 1.27 1.27) (thickness 0.15)) (justify left bottom))
      )
      (property "Value" "Molex_KK_1x4_22-27-2041" (at 13.335 -5.08 0)
        (effects (font (size 1.27 1.27) (thickness 0.15)) (justify left bottom) hide)
      )
      (property "Footprint" "antmicro-footprints:Conn_Molex_KK_1x4_22-27-2041" (at 13.335 -7.62 0)
        (effects (font (size 1.27 1.27) (thickness 0.15)) (justify left bottom) hide)
      )
      (property "Datasheet" "https://www.molex.com/en-us/products/part-detail/22272041?display=pdf" (at 13.335 -10.16 0)
        (effects (font (size 1.27 1.27) (thickness 0.15)) (justify left bottom) hide)
      )
      (property "MPN" "22-27-2041" (at 13.335 -12.7 0)
        (effects (font (size 1.27 1.27) (thickness 0.15)) (justify left bottom))
      )
      (property "Manufacturer" "Molex" (at 13.335 -15.24 0)
        (effects (font (size 1.27 1.27) (thickness 0.15)) (justify left bottom) hide)
      )
      (property "Author" "Antmicro" (at 13.335 -17.78 0)
        (effects (font (size 1.27 1.27) (thickness 0.15)) (justify left bottom) hide)
      )
      (property "License" "Apache-2.0" (at 13.335 -20.32 0)
        (effects (font (size 1.27 1.27) (thickness 0.15)) (justify left bottom) hide)
      )
      (property "ki_keywords" "VERTICAL, THT, HEADER, CONNECTOR, MALE" (at 0 0 0)
        (effects (font (size 1.27 1.27)) hide)
      )
      (property "ki_description" "Rectangular connector (header, female pins)" (at 0 0 0)
        (effects (font (size 1.27 1.27)) hide)
      )
      (symbol "Molex_KK_1x4_22-27-2041_1_1"
        (rectangle (start 2.54 -7.493) (end 3.81 -7.747)
          (stroke (width 0.254) (type default))
          (fill (type background))
        )
        (rectangle (start 2.54 -4.953) (end 3.81 -5.207)
          (stroke (width 0.254) (type default))
          (fill (type background))
        )
        (rectangle (start 2.54 -2.413) (end 3.81 -2.667)
          (stroke (width 0.254) (type default))
          (fill (type background))
        )
        (rectangle (start 2.54 0.127) (end 3.81 -0.127)
          (stroke (width 0.254) (type default))
          (fill (type background))
        )
        (rectangle (start 2.54 1.27) (end 5.08 -8.89)
          (stroke (width 0.254) (type default))
          (fill (type background))
        )
        (pin passive line (at 0 0 0) (length 2.54)
          (name "~" (effects (font (size 1.27 1.27))))
          (number "1" (effects (font (size 1.27 1.27))))
        )
        (pin passive line (at 0 -2.54 0) (length 2.54)
          (name "~" (effects (font (size 1.27 1.27))))
          (number "2" (effects (font (size 1.27 1.27))))
        )
        (pin passive line (at 0 -5.08 0) (length 2.54)
          (name "~" (effects (font (size 1.27 1.27))))
          (number "3" (effects (font (size 1.27 1.27))))
        )
        (pin passive line (at 0 -7.62 0) (length 2.54)
          (name "~" (effects (font (size 1.27 1.27))))
          (number "4" (effects (font (size 1.27 1.27))))
        )
      )
    )
	(symbol "antmicroWire2BoardConnectors:Molex_Mini-Fit-Jr_2x4_39-28-8080" (in_bom yes) (on_board yes)
      (property "Reference" "J" (at 26.67 -3.81 0)
        (effects (font (size 1.27 1.27) (thickness 0.15)) (justify left bottom))
      )
      (property "Value" "Molex_Mini-Fit-Jr_2x4_39-28-8080" (at 26.67 -8.89 0)
        (effects (font (size 1.27 1.27) (thickness 0.15)) (justify left bottom) hide)
      )
      (property "Footprint" "antmicro-footprints:MOLEX_39288080" (at 26.67 -11.43 0)
        (effects (font (size 1.27 1.27) (thickness 0.15)) (justify left bottom) hide)
      )
      (property "Datasheet" "https://www.molex.com/pdm_docs/sd/039288080_sd.pdf" (at 26.67 -13.97 0)
        (effects (font (size 1.27 1.27) (thickness 0.15)) (justify left bottom) hide)
      )
      (property "MPN" "39-28-8080" (at 26.67 -6.35 0)
        (effects (font (size 1.27 1.27) (thickness 0.15)) (justify left bottom))
      )
      (property "Manufacturer" "Molex" (at 26.67 -16.51 0)
        (effects (font (size 1.27 1.27) (thickness 0.15)) (justify left bottom) hide)
      )
      (property "Author" "Antmicro" (at 26.67 -19.05 0)
        (effects (font (size 1.27 1.27) (thickness 0.15)) (justify left bottom) hide)
      )
      (property "License" "Apache-2.0" (at 26.67 -21.59 0)
        (effects (font (size 1.27 1.27) (thickness 0.15)) (justify left bottom) hide)
      )
      (property "ki_keywords" "VERTICAL, THT, HEADER, CONNECTOR, MALE, WIRE-BOARD, POWER" (at 0 0 0)
        (effects (font (size 1.27 1.27)) hide)
      )
      (property "ki_description" "Pin Header, THT, Vertical, UL94V-2, Power, Wire-to-Board, 4.2 mm, 2 Rows, 8 Contacts, Mini-fit Jr, 5566 series" (at 0 0 0)
        (effects (font (size 1.27 1.27)) hide)
      )
      (symbol "Molex_Mini-Fit-Jr_2x4_39-28-8080_1_1"
        (rectangle (start 2.54 -3.175) (end 2.794 -4.445)
          (stroke (width 0.254) (type default))
          (fill (type background))
        )
        (rectangle (start 2.54 1.27) (end 10.16 -8.89)
          (stroke (width 0.254) (type default))
          (fill (type background))
        )
        (pin bidirectional line (at 12.7 0 180) (length 2.54)
          (name "1" (effects (font (size 1.27 1.27))))
          (number "1" (effects (font (size 1.27 1.27))))
        )
        (pin bidirectional line (at 12.7 -2.54 180) (length 2.54)
          (name "2" (effects (font (size 1.27 1.27))))
          (number "2" (effects (font (size 1.27 1.27))))
        )
        (pin bidirectional line (at 12.7 -5.08 180) (length 2.54)
          (name "3" (effects (font (size 1.27 1.27))))
          (number "3" (effects (font (size 1.27 1.27))))
        )
        (pin bidirectional line (at 12.7 -7.62 180) (length 2.54)
          (name "4" (effects (font (size 1.27 1.27))))
          (number "4" (effects (font (size 1.27 1.27))))
        )
        (pin bidirectional line (at 0 0 0) (length 2.54)
          (name "5" (effects (font (size 1.27 1.27))))
          (number "5" (effects (font (size 1.27 1.27))))
        )
        (pin bidirectional line (at 0 -2.54 0) (length 2.54)
          (name "6" (effects (font (size 1.27 1.27))))
          (number "6" (effects (font (size 1.27 1.27))))
        )
        (pin bidirectional line (at 0 -5.08 0) (length 2.54)
          (name "7" (effects (font (size 1.27 1.27))))
          (number "7" (effects (font (size 1.27 1.27))))
        )
        (pin bidirectional line (at 0 -7.62 0) (length 2.54)
          (name "8" (effects (font (size 1.27 1.27))))
          (number "8" (effects (font (size 1.27 1.27))))
        )
      )
    )
	(symbol "antmicroWire2BoardConnectors:Molex_Mini-Fit-Jr_2x5_39-28-1103" (in_bom yes) (on_board yes)
      (property "Reference" "J" (at 25.4 -5.08 0)
        (effects (font (size 1.27 1.27) (thickness 0.15)) (justify left bottom))
      )
      (property "Value" "Molex_Mini-Fit-Jr_2x5_39-28-1103" (at 25.4 -10.16 0)
        (effects (font (size 1.27 1.27) (thickness 0.15)) (justify left bottom) hide)
      )
      (property "Footprint" "antmicro-footprints:MOLEX_39281103" (at 25.4 -12.7 0)
        (effects (font (size 1.27 1.27) (thickness 0.15)) (justify left bottom) hide)
      )
      (property "Datasheet" "https://www.molex.com/pdm_docs/sd/039281103_sd.pdf" (at 25.4 -15.24 0)
        (effects (font (size 1.27 1.27) (thickness 0.15)) (justify left bottom) hide)
      )
      (property "MPN" "39-28-1103" (at 25.4 -7.62 0)
        (effects (font (size 1.27 1.27) (thickness 0.15)) (justify left bottom))
      )
      (property "Manufacturer" "Molex" (at 25.4 -17.78 0)
        (effects (font (size 1.27 1.27) (thickness 0.15)) (justify left bottom) hide)
      )
      (property "Author" "Antmicro" (at 25.4 -20.32 0)
        (effects (font (size 1.27 1.27) (thickness 0.15)) (justify left bottom) hide)
      )
      (property "License" "Apache-2.0" (at 25.4 -22.86 0)
        (effects (font (size 1.27 1.27) (thickness 0.15)) (justify left bottom) hide)
      )
      (property "ki_keywords" "VERTICAL, THT, HEADER, CONNECTOR, MALE, WIRE-BOARD" (at 0 0 0)
        (effects (font (size 1.27 1.27)) hide)
      )
      (property "ki_description" "Pin Header, THT, Vertical, UL94V-2, Power, Wire-to-Board, 4.2 mm, 2 Rows, 10 Contacts, Mini-fit Jr, 5566 series" (at 0 0 0)
        (effects (font (size 1.27 1.27)) hide)
      )
      (symbol "Molex_Mini-Fit-Jr_2x5_39-28-1103_1_1"
        (rectangle (start 2.54 -4.445) (end 2.794 -5.715)
          (stroke (width 0.254) (type default))
          (fill (type background))
        )
        (rectangle (start 2.54 1.27) (end 10.16 -11.43)
          (stroke (width 0.254) (type default))
          (fill (type background))
        )
        (pin bidirectional line (at 12.7 0 180) (length 2.54)
          (name "1" (effects (font (size 1.27 1.27))))
          (number "1" (effects (font (size 1.27 1.27))))
        )
        (pin bidirectional line (at 0 -10.16 0) (length 2.54)
          (name "10" (effects (font (size 1.27 1.27))))
          (number "10" (effects (font (size 1.27 1.27))))
        )
        (pin bidirectional line (at 12.7 -2.54 180) (length 2.54)
          (name "2" (effects (font (size 1.27 1.27))))
          (number "2" (effects (font (size 1.27 1.27))))
        )
        (pin bidirectional line (at 12.7 -5.08 180) (length 2.54)
          (name "3" (effects (font (size 1.27 1.27))))
          (number "3" (effects (font (size 1.27 1.27))))
        )
        (pin bidirectional line (at 12.7 -7.62 180) (length 2.54)
          (name "4" (effects (font (size 1.27 1.27))))
          (number "4" (effects (font (size 1.27 1.27))))
        )
        (pin bidirectional line (at 12.7 -10.16 180) (length 2.54)
          (name "5" (effects (font (size 1.27 1.27))))
          (number "5" (effects (font (size 1.27 1.27))))
        )
        (pin bidirectional line (at 0 0 0) (length 2.54)
          (name "6" (effects (font (size 1.27 1.27))))
          (number "6" (effects (font (size 1.27 1.27))))
        )
        (pin bidirectional line (at 0 -2.54 0) (length 2.54)
          (name "7" (effects (font (size 1.27 1.27))))
          (number "7" (effects (font (size 1.27 1.27))))
        )
        (pin bidirectional line (at 0 -5.08 0) (length 2.54)
          (name "8" (effects (font (size 1.27 1.27))))
          (number "8" (effects (font (size 1.27 1.27))))
        )
        (pin bidirectional line (at 0 -7.62 0) (length 2.54)
          (name "9" (effects (font (size 1.27 1.27))))
          (number "9" (effects (font (size 1.27 1.27))))
        )
      )
    )
	(symbol "antmicropower:GND" (power) (pin_numbers hide) (pin_names hide) (in_bom yes) (on_board yes)
      (property "Reference" "#PWR" (at 8.89 -2.54 0)
        (effects (font (size 1.27 1.27) (thickness 0.15)) (justify left bottom) hide)
      )
      (property "Value" "GND" (at 8.89 -5.08 0)
        (effects (font (size 1.27 1.27) (thickness 0.15)) (justify left bottom))
      )
      (property "Footprint" "" (at 8.89 -7.62 0)
        (effects (font (size 1.27 1.27) (thickness 0.15)) (justify left bottom) hide)
      )
      (property "Datasheet" "" (at 8.89 -12.7 0)
        (effects (font (size 1.27 1.27) (thickness 0.15)) (justify left bottom) hide)
      )
      (property "Author" "Antmicro" (at 8.89 -7.62 0)
        (effects (font (size 1.27 1.27) (thickness 0.15)) (justify left bottom) hide)
      )
      (property "License" "Apache-2.0" (at 8.89 -10.16 0)
        (effects (font (size 1.27 1.27) (thickness 0.15)) (justify left bottom) hide)
      )
      (symbol "GND_1_1"
        (polyline
          (pts
            (xy 0 0)
            (xy 0 -1.27)
            (xy 1.27 -1.27)
            (xy 0 -2.54)
            (xy -1.27 -1.27)
            (xy 0 -1.27)
          )
          (stroke (width 0) (type default))
          (fill (type none))
        )
        (pin power_in line (at 0 0 270) (length 0)
          (name "GND" (effects (font (size 1.27 1.27))))
          (number "1" (effects (font (size 1.27 1.27))))
        )
      )
    )
	(symbol "antmicropower:GNDD" (power) (pin_numbers hide) (pin_names hide) (in_bom yes) (on_board yes)
      (property "Reference" "#PWR" (at 15.24 -2.54 0)
        (effects (font (size 1.27 1.27) (thickness 0.15)) (justify left bottom) hide)
      )
      (property "Value" "GNDD" (at 15.24 -5.08 0)
        (effects (font (size 1.27 1.27) (thickness 0.15)) (justify left bottom))
      )
      (property "Footprint" "" (at 15.24 -10.16 0)
        (effects (font (size 1.27 1.27) (thickness 0.15)) (justify left bottom) hide)
      )
      (property "Datasheet" "" (at 15.24 -12.7 0)
        (effects (font (size 1.27 1.27) (thickness 0.15)) (justify left bottom) hide)
      )
      (property "Author" "Antmicro" (at 15.24 -7.62 0)
        (effects (font (size 1.27 1.27) (thickness 0.15)) (justify left bottom) hide)
      )
      (property "License" "Apache-2.0" (at 15.24 -10.16 0)
        (effects (font (size 1.27 1.27) (thickness 0.15)) (justify left bottom) hide)
      )
      (symbol "GNDD_1_1"
        (rectangle (start -1.27 -1.524) (end 1.27 -2.032)
          (stroke (width 0) (type default))
          (fill (type outline))
        )
        (polyline
          (pts
            (xy 0 0)
            (xy 0 -1.524)
          )
          (stroke (width 0) (type default))
          (fill (type background))
        )
        (pin power_in line (at 0 0 270) (length 0)
          (name "GNDD" (effects (font (size 1.27 1.27))))
          (number "1" (effects (font (size 1.27 1.27))))
        )
      )
    )
)
